G04 ================== begin FILE IDENTIFICATION RECORD ==================*
G04 Layout Name:  D:/<user>/Wistron_project/16318-2/gbr/16318-2.brd*
G04 Film Name:    L8*
G04 File Format:  Gerber RS274X*
G04 File Origin:  Cadence Allegro 16.5-S056*
G04 Origin Date:  Mon Aug 07 11:09:53 2017*
G04 *
G04 Layer:  VIA CLASS/BOTTOM*
G04 Layer:  PIN/BOTTOM*
G04 Layer:  ETCH/BOTTOM*
G04 Layer:  DRAWING FORMAT/LAYER_PCB_STORY*
G04 Layer:  DRAWING FORMAT/LAYER_L8*
G04 *
G04 Offset:    (0.00 0.00)*
G04 Mirror:    No*
G04 Mode:      Positive*
G04 Rotation:  0*
G04 FullContactRelief:  No*
G04 UndefLineWidth:     6.00*
G04 ================== end FILE IDENTIFICATION RECORD ====================*
%FSLAX35Y35*MOIN*%
%IR0*IPPOS*OFA0.00000B0.00000*MIA0B0*SFA1.00000B1.00000*%
%AMMACRO32*
4,1,40,.011,.007,
.011,-.007,
.010939,-.007695,
.010759,-.008368,
.010464,-.009,
.010064,-.009571,
.009571,-.010064,
.009,-.010464,
.008368,-.010759,
.007695,-.010939,
.007,-.011,
-.007,-.011,
-.007695,-.010939,
-.008368,-.010759,
-.009,-.010464,
-.009571,-.010064,
-.010064,-.009571,
-.010464,-.009,
-.010759,-.008368,
-.010939,-.007695,
-.011,-.007,
-.011,.007,
-.010939,.007695,
-.010759,.008368,
-.010464,.009,
-.010064,.009571,
-.009571,.010064,
-.009,.010464,
-.008368,.010759,
-.007695,.010939,
-.007,.011,
.007,.011,
.007695,.010939,
.008368,.010759,
.009,.010464,
.009571,.010064,
.010064,.009571,
.010464,.009,
.010759,.008368,
.010939,.007695,
.011,.007,
0.0*
%
%ADD32MACRO32*%
%AMMACRO26*
4,1,40,.013,-.017,
-.013,-.017,
-.013695,-.016939,
-.014368,-.016759,
-.015,-.016464,
-.015571,-.016064,
-.016064,-.015571,
-.016464,-.015,
-.016759,-.014368,
-.016939,-.013695,
-.017,-.013,
-.017,.013,
-.016939,.013695,
-.016759,.014368,
-.016464,.015,
-.016064,.015571,
-.015571,.016064,
-.015,.016464,
-.014368,.016759,
-.013695,.016939,
-.013,.017,
.013,.017,
.013695,.016939,
.014368,.016759,
.015,.016464,
.015571,.016064,
.016064,.015571,
.016464,.015,
.016759,.014368,
.016939,.013695,
.017,.013,
.017,-.013,
.016939,-.013695,
.016759,-.014368,
.016464,-.015,
.016064,-.015571,
.015571,-.016064,
.015,-.016464,
.014368,-.016759,
.013695,-.016939,
.013,-.017,
0.0*
%
%ADD26MACRO26*%
%AMMACRO24*
4,1,40,-.017,-.013,
-.017,.013,
-.016939,.013695,
-.016759,.014368,
-.016464,.015,
-.016064,.015571,
-.015571,.016064,
-.015,.016464,
-.014368,.016759,
-.013695,.016939,
-.013,.017,
.013,.017,
.013695,.016939,
.014368,.016759,
.015,.016464,
.015571,.016064,
.016064,.015571,
.016464,.015,
.016759,.014368,
.016939,.013695,
.017,.013,
.017,-.013,
.016939,-.013695,
.016759,-.014368,
.016464,-.015,
.016064,-.015571,
.015571,-.016064,
.015,-.016464,
.014368,-.016759,
.013695,-.016939,
.013,-.017,
-.013,-.017,
-.013695,-.016939,
-.014368,-.016759,
-.015,-.016464,
-.015571,-.016064,
-.016064,-.015571,
-.016464,-.015,
-.016759,-.014368,
-.016939,-.013695,
-.017,-.013,
0.0*
%
%ADD24MACRO24*%
%ADD50O,.06X.111*%
%ADD12C,.01*%
%ADD13C,.02*%
%ADD60C,.03*%
%ADD44C,.04*%
%ADD28C,.022*%
%ADD61C,.05*%
%ADD46C,.032*%
%AMMACRO73*
4,1,40,-.007,-.004,
-.007,.004,
-.00697,.004347,
-.006879,.004684,
-.006732,.005,
-.006532,.005286,
-.006286,.005532,
-.006,.005732,
-.005684,.005879,
-.005347,.00597,
-.005,.006,
.005,.006,
.005347,.00597,
.005684,.005879,
.006,.005732,
.006286,.005532,
.006532,.005286,
.006732,.005,
.006879,.004684,
.00697,.004347,
.007,.004,
.007,-.004,
.00697,-.004347,
.006879,-.004684,
.006732,-.005,
.006532,-.005286,
.006286,-.005532,
.006,-.005732,
.005684,-.005879,
.005347,-.00597,
.005,-.006,
-.005,-.006,
-.005347,-.00597,
-.005684,-.005879,
-.006,-.005732,
-.006286,-.005532,
-.006532,-.005286,
-.006732,-.005,
-.006879,-.004684,
-.00697,-.004347,
-.007,-.004,
0.0*
%
%ADD73MACRO73*%
%ADD53C,.042*%
%ADD27C,.024*%
%AMMACRO67*
4,1,40,-.004,.007,
.004,.007,
.004347,.00697,
.004684,.006879,
.005,.006732,
.005286,.006532,
.005532,.006286,
.005732,.006,
.005879,.005684,
.00597,.005347,
.006,.005,
.006,-.005,
.00597,-.005347,
.005879,-.005684,
.005732,-.006,
.005532,-.006286,
.005286,-.006532,
.005,-.006732,
.004684,-.006879,
.004347,-.00697,
.004,-.007,
-.004,-.007,
-.004347,-.00697,
-.004684,-.006879,
-.005,-.006732,
-.005286,-.006532,
-.005532,-.006286,
-.005732,-.006,
-.005879,-.005684,
-.00597,-.005347,
-.006,-.005,
-.006,.005,
-.00597,.005347,
-.005879,.005684,
-.005732,.006,
-.005532,.006286,
-.005286,.006532,
-.005,.006732,
-.004684,.006879,
-.004347,.00697,
-.004,.007,
0.0*
%
%ADD67MACRO67*%
%ADD66C,.036*%
%ADD47C,.018*%
%ADD10C,.028*%
%ADD65C,.029*%
%ADD11C,.056*%
%AMMACRO59*
4,1,40,.0225,.007,
.022378,.008389,
.022018,.009736,
.021428,.011,
.020628,.012142,
.019642,.013128,
.0185,.013928,
.017236,.014518,
.015889,.014878,
.0145,.015,
-.0145,.015,
-.015889,.014878,
-.017236,.014518,
-.0185,.013928,
-.019642,.013128,
-.020628,.012142,
-.021428,.011,
-.022018,.009736,
-.022378,.008389,
-.0225,.007,
-.0225,-.007,
-.022378,-.008389,
-.022018,-.009736,
-.021428,-.011,
-.020628,-.012142,
-.019642,-.013128,
-.0185,-.013928,
-.017236,-.014518,
-.015889,-.014878,
-.0145,-.015,
.0145,-.015,
.015889,-.014878,
.017236,-.014518,
.0185,-.013928,
.019642,-.013128,
.020628,-.012142,
.021428,-.011,
.022018,-.009736,
.022378,-.008389,
.0225,-.007,
.0225,.007,
0.0*
%
%ADD59MACRO59*%
%AMMACRO58*
4,1,40,.008,.014,
-.008,.014,
-.008695,.013939,
-.009368,.013759,
-.01,.013464,
-.010571,.013064,
-.011064,.012571,
-.011464,.012,
-.011759,.011368,
-.011939,.010695,
-.012,.01,
-.012,-.01,
-.011939,-.010695,
-.011759,-.011368,
-.011464,-.012,
-.011064,-.012571,
-.010571,-.013064,
-.01,-.013464,
-.009368,-.013759,
-.008695,-.013939,
-.008,-.014,
.008,-.014,
.008695,-.013939,
.009368,-.013759,
.01,-.013464,
.010571,-.013064,
.011064,-.012571,
.011464,-.012,
.011759,-.011368,
.011939,-.010695,
.012,-.01,
.012,.01,
.011939,.010695,
.011759,.011368,
.011464,.012,
.011064,.012571,
.010571,.013064,
.01,.013464,
.009368,.013759,
.008695,.013939,
.008,.014,
0.0*
%
%ADD58MACRO58*%
%AMMACRO57*
4,1,40,.014,-.008,
.014,.008,
.013939,.008695,
.013759,.009368,
.013464,.01,
.013064,.010571,
.012571,.011064,
.012,.011464,
.011368,.011759,
.010695,.011939,
.01,.012,
-.01,.012,
-.010695,.011939,
-.011368,.011759,
-.012,.011464,
-.012571,.011064,
-.013064,.010571,
-.013464,.01,
-.013759,.009368,
-.013939,.008695,
-.014,.008,
-.014,-.008,
-.013939,-.008695,
-.013759,-.009368,
-.013464,-.01,
-.013064,-.010571,
-.012571,-.011064,
-.012,-.011464,
-.011368,-.011759,
-.010695,-.011939,
-.01,-.012,
.01,-.012,
.010695,-.011939,
.011368,-.011759,
.012,-.011464,
.012571,-.011064,
.013064,-.010571,
.013464,-.01,
.013759,-.009368,
.013939,-.008695,
.014,-.008,
0.0*
%
%ADD57MACRO57*%
%AMMACRO22*
4,1,40,.007,-.011,
-.007,-.011,
-.007695,-.010939,
-.008368,-.010759,
-.009,-.010464,
-.009571,-.010064,
-.010064,-.009571,
-.010464,-.009,
-.010759,-.008368,
-.010939,-.007695,
-.011,-.007,
-.011,.007,
-.010939,.007695,
-.010759,.008368,
-.010464,.009,
-.010064,.009571,
-.009571,.010064,
-.009,.010464,
-.008368,.010759,
-.007695,.010939,
-.007,.011,
.007,.011,
.007695,.010939,
.008368,.010759,
.009,.010464,
.009571,.010064,
.010064,.009571,
.010464,.009,
.010759,.008368,
.010939,.007695,
.011,.007,
.011,-.007,
.010939,-.007695,
.010759,-.008368,
.010464,-.009,
.010064,-.009571,
.009571,-.010064,
.009,-.010464,
.008368,-.010759,
.007695,-.010939,
.007,-.011,
0.0*
%
%ADD22MACRO22*%
%AMMACRO15*
4,1,40,-.011,-.007,
-.011,.007,
-.010939,.007695,
-.010759,.008368,
-.010464,.009,
-.010064,.009571,
-.009571,.010064,
-.009,.010464,
-.008368,.010759,
-.007695,.010939,
-.007,.011,
.007,.011,
.007695,.010939,
.008368,.010759,
.009,.010464,
.009571,.010064,
.010064,.009571,
.010464,.009,
.010759,.008368,
.010939,.007695,
.011,.007,
.011,-.007,
.010939,-.007695,
.010759,-.008368,
.010464,-.009,
.010064,-.009571,
.009571,-.010064,
.009,-.010464,
.008368,-.010759,
.007695,-.010939,
.007,-.011,
-.007,-.011,
-.007695,-.010939,
-.008368,-.010759,
-.009,-.010464,
-.009571,-.010064,
-.010064,-.009571,
-.010464,-.009,
-.010759,-.008368,
-.010939,-.007695,
-.011,-.007,
0.0*
%
%ADD15MACRO15*%
%AMMACRO36*
4,1,40,-.012,-.008,
-.012,.008,
-.011939,.008695,
-.011759,.009368,
-.011464,.01,
-.011064,.010571,
-.010571,.011064,
-.01,.011464,
-.009368,.011759,
-.008695,.011939,
-.008,.012,
.008,.012,
.008695,.011939,
.009368,.011759,
.01,.011464,
.010571,.011064,
.011064,.010571,
.011464,.01,
.011759,.009368,
.011939,.008695,
.012,.008,
.012,-.008,
.011939,-.008695,
.011759,-.009368,
.011464,-.01,
.011064,-.010571,
.010571,-.011064,
.01,-.011464,
.009368,-.011759,
.008695,-.011939,
.008,-.012,
-.008,-.012,
-.008695,-.011939,
-.009368,-.011759,
-.01,-.011464,
-.010571,-.011064,
-.011064,-.010571,
-.011464,-.01,
-.011759,-.009368,
-.011939,-.008695,
-.012,-.008,
0.0*
%
%ADD36MACRO36*%
%AMMACRO38*
4,1,40,-.008,.012,
.008,.012,
.008695,.011939,
.009368,.011759,
.01,.011464,
.010571,.011064,
.011064,.010571,
.011464,.01,
.011759,.009368,
.011939,.008695,
.012,.008,
.012,-.008,
.011939,-.008695,
.011759,-.009368,
.011464,-.01,
.011064,-.010571,
.010571,-.011064,
.01,-.011464,
.009368,-.011759,
.008695,-.011939,
.008,-.012,
-.008,-.012,
-.008695,-.011939,
-.009368,-.011759,
-.01,-.011464,
-.010571,-.011064,
-.011064,-.010571,
-.011464,-.01,
-.011759,-.009368,
-.011939,-.008695,
-.012,-.008,
-.012,.008,
-.011939,.008695,
-.011759,.009368,
-.011464,.01,
-.011064,.010571,
-.010571,.011064,
-.01,.011464,
-.009368,.011759,
-.008695,.011939,
-.008,.012,
0.0*
%
%ADD38MACRO38*%
%AMMACRO40*
4,1,40,-.013,.017,
.013,.017,
.013695,.016939,
.014368,.016759,
.015,.016464,
.015571,.016064,
.016064,.015571,
.016464,.015,
.016759,.014368,
.016939,.013695,
.017,.013,
.017,-.013,
.016939,-.013695,
.016759,-.014368,
.016464,-.015,
.016064,-.015571,
.015571,-.016064,
.015,-.016464,
.014368,-.016759,
.013695,-.016939,
.013,-.017,
-.013,-.017,
-.013695,-.016939,
-.014368,-.016759,
-.015,-.016464,
-.015571,-.016064,
-.016064,-.015571,
-.016464,-.015,
-.016759,-.014368,
-.016939,-.013695,
-.017,-.013,
-.017,.013,
-.016939,.013695,
-.016759,.014368,
-.016464,.015,
-.016064,.015571,
-.015571,.016064,
-.015,.016464,
-.014368,.016759,
-.013695,.016939,
-.013,.017,
0.0*
%
%ADD40MACRO40*%
%AMMACRO42*
4,1,40,.017,.013,
.017,-.013,
.016939,-.013695,
.016759,-.014368,
.016464,-.015,
.016064,-.015571,
.015571,-.016064,
.015,-.016464,
.014368,-.016759,
.013695,-.016939,
.013,-.017,
-.013,-.017,
-.013695,-.016939,
-.014368,-.016759,
-.015,-.016464,
-.015571,-.016064,
-.016064,-.015571,
-.016464,-.015,
-.016759,-.014368,
-.016939,-.013695,
-.017,-.013,
-.017,.013,
-.016939,.013695,
-.016759,.014368,
-.016464,.015,
-.016064,.015571,
-.015571,.016064,
-.015,.016464,
-.014368,.016759,
-.013695,.016939,
-.013,.017,
.013,.017,
.013695,.016939,
.014368,.016759,
.015,.016464,
.015571,.016064,
.016064,.015571,
.016464,.015,
.016759,.014368,
.016939,.013695,
.017,.013,
0.0*
%
%ADD42MACRO42*%
%AMMACRO74*
4,1,6,-.0135,-.005,
-.0065,-.005,
.0135,-.025,
.0135,.025,
-.0065,.005,
-.0135,.005,
-.0135,-.005,
0.0*
%
%ADD74MACRO74*%
%AMMACRO33*
4,1,40,.007,-.011,
-.007,-.011,
-.007695,-.010939,
-.008368,-.010759,
-.009,-.010464,
-.009571,-.010064,
-.010064,-.009571,
-.010464,-.009,
-.010759,-.008368,
-.010939,-.007695,
-.011,-.007,
-.011,.007,
-.010939,.007695,
-.010759,.008368,
-.010464,.009,
-.010064,.009571,
-.009571,.010064,
-.009,.010464,
-.008368,.010759,
-.007695,.010939,
-.007,.011,
.007,.011,
.007695,.010939,
.008368,.010759,
.009,.010464,
.009571,.010064,
.010064,.009571,
.010464,.009,
.010759,.008368,
.010939,.007695,
.011,.007,
.011,-.007,
.010939,-.007695,
.010759,-.008368,
.010464,-.009,
.010064,-.009571,
.009571,-.010064,
.009,-.010464,
.008368,-.010759,
.007695,-.010939,
.007,-.011,
0.0*
%
%ADD33MACRO33*%
%AMMACRO16*
4,1,40,-.011,-.007,
-.011,.007,
-.010939,.007695,
-.010759,.008368,
-.010464,.009,
-.010064,.009571,
-.009571,.010064,
-.009,.010464,
-.008368,.010759,
-.007695,.010939,
-.007,.011,
.007,.011,
.007695,.010939,
.008368,.010759,
.009,.010464,
.009571,.010064,
.010064,.009571,
.010464,.009,
.010759,.008368,
.010939,.007695,
.011,.007,
.011,-.007,
.010939,-.007695,
.010759,-.008368,
.010464,-.009,
.010064,-.009571,
.009571,-.010064,
.009,-.010464,
.008368,-.010759,
.007695,-.010939,
.007,-.011,
-.007,-.011,
-.007695,-.010939,
-.008368,-.010759,
-.009,-.010464,
-.009571,-.010064,
-.010064,-.009571,
-.010464,-.009,
-.010759,-.008368,
-.010939,-.007695,
-.011,-.007,
0.0*
%
%ADD16MACRO16*%
%AMMACRO35*
4,1,40,-.012,-.008,
-.012,.008,
-.011939,.008695,
-.011759,.009368,
-.011464,.01,
-.011064,.010571,
-.010571,.011064,
-.01,.011464,
-.009368,.011759,
-.008695,.011939,
-.008,.012,
.008,.012,
.008695,.011939,
.009368,.011759,
.01,.011464,
.010571,.011064,
.011064,.010571,
.011464,.01,
.011759,.009368,
.011939,.008695,
.012,.008,
.012,-.008,
.011939,-.008695,
.011759,-.009368,
.011464,-.01,
.011064,-.010571,
.010571,-.011064,
.01,-.011464,
.009368,-.011759,
.008695,-.011939,
.008,-.012,
-.008,-.012,
-.008695,-.011939,
-.009368,-.011759,
-.01,-.011464,
-.010571,-.011064,
-.011064,-.010571,
-.011464,-.01,
-.011759,-.009368,
-.011939,-.008695,
-.012,-.008,
0.0*
%
%ADD35MACRO35*%
%AMMACRO37*
4,1,40,-.008,.012,
.008,.012,
.008695,.011939,
.009368,.011759,
.01,.011464,
.010571,.011064,
.011064,.010571,
.011464,.01,
.011759,.009368,
.011939,.008695,
.012,.008,
.012,-.008,
.011939,-.008695,
.011759,-.009368,
.011464,-.01,
.011064,-.010571,
.010571,-.011064,
.01,-.011464,
.009368,-.011759,
.008695,-.011939,
.008,-.012,
-.008,-.012,
-.008695,-.011939,
-.009368,-.011759,
-.01,-.011464,
-.010571,-.011064,
-.011064,-.010571,
-.011464,-.01,
-.011759,-.009368,
-.011939,-.008695,
-.012,-.008,
-.012,.008,
-.011939,.008695,
-.011759,.009368,
-.011464,.01,
-.011064,.010571,
-.010571,.011064,
-.01,.011464,
-.009368,.011759,
-.008695,.011939,
-.008,.012,
0.0*
%
%ADD37MACRO37*%
%AMMACRO41*
4,1,40,-.013,.017,
.013,.017,
.013695,.016939,
.014368,.016759,
.015,.016464,
.015571,.016064,
.016064,.015571,
.016464,.015,
.016759,.014368,
.016939,.013695,
.017,.013,
.017,-.013,
.016939,-.013695,
.016759,-.014368,
.016464,-.015,
.016064,-.015571,
.015571,-.016064,
.015,-.016464,
.014368,-.016759,
.013695,-.016939,
.013,-.017,
-.013,-.017,
-.013695,-.016939,
-.014368,-.016759,
-.015,-.016464,
-.015571,-.016064,
-.016064,-.015571,
-.016464,-.015,
-.016759,-.014368,
-.016939,-.013695,
-.017,-.013,
-.017,.013,
-.016939,.013695,
-.016759,.014368,
-.016464,.015,
-.016064,.015571,
-.015571,.016064,
-.015,.016464,
-.014368,.016759,
-.013695,.016939,
-.013,.017,
0.0*
%
%ADD41MACRO41*%
%AMMACRO43*
4,1,40,.017,.013,
.017,-.013,
.016939,-.013695,
.016759,-.014368,
.016464,-.015,
.016064,-.015571,
.015571,-.016064,
.015,-.016464,
.014368,-.016759,
.013695,-.016939,
.013,-.017,
-.013,-.017,
-.013695,-.016939,
-.014368,-.016759,
-.015,-.016464,
-.015571,-.016064,
-.016064,-.015571,
-.016464,-.015,
-.016759,-.014368,
-.016939,-.013695,
-.017,-.013,
-.017,.013,
-.016939,.013695,
-.016759,.014368,
-.016464,.015,
-.016064,.015571,
-.015571,.016064,
-.015,.016464,
-.014368,.016759,
-.013695,.016939,
-.013,.017,
.013,.017,
.013695,.016939,
.014368,.016759,
.015,.016464,
.015571,.016064,
.016064,.015571,
.016464,.015,
.016759,.014368,
.016939,.013695,
.017,.013,
0.0*
%
%ADD43MACRO43*%
%ADD68R,.012X.06*%
%ADD62R,.016X.02*%
%ADD45R,.06X.014*%
%AMMACRO72*
4,1,40,.007,.004,
.007,-.004,
.00697,-.004347,
.006879,-.004684,
.006732,-.005,
.006532,-.005286,
.006286,-.005532,
.006,-.005732,
.005684,-.005879,
.005347,-.00597,
.005,-.006,
-.005,-.006,
-.005347,-.00597,
-.005684,-.005879,
-.006,-.005732,
-.006286,-.005532,
-.006532,-.005286,
-.006732,-.005,
-.006879,-.004684,
-.00697,-.004347,
-.007,-.004,
-.007,.004,
-.00697,.004347,
-.006879,.004684,
-.006732,.005,
-.006532,.005286,
-.006286,.005532,
-.006,.005732,
-.005684,.005879,
-.005347,.00597,
-.005,.006,
.005,.006,
.005347,.00597,
.005684,.005879,
.006,.005732,
.006286,.005532,
.006532,.005286,
.006732,.005,
.006879,.004684,
.00697,.004347,
.007,.004,
0.0*
%
%ADD72MACRO72*%
%AMMACRO69*
4,1,40,.004,-.007,
-.004,-.007,
-.004347,-.00697,
-.004684,-.006879,
-.005,-.006732,
-.005286,-.006532,
-.005532,-.006286,
-.005732,-.006,
-.005879,-.005684,
-.00597,-.005347,
-.006,-.005,
-.006,.005,
-.00597,.005347,
-.005879,.005684,
-.005732,.006,
-.005532,.006286,
-.005286,.006532,
-.005,.006732,
-.004684,.006879,
-.004347,.00697,
-.004,.007,
.004,.007,
.004347,.00697,
.004684,.006879,
.005,.006732,
.005286,.006532,
.005532,.006286,
.005732,.006,
.005879,.005684,
.00597,.005347,
.006,.005,
.006,-.005,
.00597,-.005347,
.005879,-.005684,
.005732,-.006,
.005532,-.006286,
.005286,-.006532,
.005,-.006732,
.004684,-.006879,
.004347,-.00697,
.004,-.007,
0.0*
%
%ADD69MACRO69*%
%ADD64C,.15*%
%ADD54R,.05X.065*%
%ADD51O,.06X.084*%
%ADD70R,.065X.05*%
%ADD34R,.048X.016*%
%ADD21R,.045X.055*%
%ADD49R,.016X.048*%
%ADD39R,.055X.045*%
%ADD63R,.067X.043*%
%ADD48C,.256*%
%ADD14C,.375*%
%AMMACRO56*
4,1,40,-.014,.008,
-.014,-.008,
-.013939,-.008695,
-.013759,-.009368,
-.013464,-.01,
-.013064,-.010571,
-.012571,-.011064,
-.012,-.011464,
-.011368,-.011759,
-.010695,-.011939,
-.01,-.012,
.01,-.012,
.010695,-.011939,
.011368,-.011759,
.012,-.011464,
.012571,-.011064,
.013064,-.010571,
.013464,-.01,
.013759,-.009368,
.013939,-.008695,
.014,-.008,
.014,.008,
.013939,.008695,
.013759,.009368,
.013464,.01,
.013064,.010571,
.012571,.011064,
.012,.011464,
.011368,.011759,
.010695,.011939,
.01,.012,
-.01,.012,
-.010695,.011939,
-.011368,.011759,
-.012,.011464,
-.012571,.011064,
-.013064,.010571,
-.013464,.01,
-.013759,.009368,
-.013939,.008695,
-.014,.008,
0.0*
%
%ADD56MACRO56*%
%AMMACRO55*
4,1,40,-.0225,-.007,
-.022378,-.008389,
-.022018,-.009736,
-.021428,-.011,
-.020628,-.012142,
-.019642,-.013128,
-.0185,-.013928,
-.017236,-.014518,
-.015889,-.014878,
-.0145,-.015,
.0145,-.015,
.015889,-.014878,
.017236,-.014518,
.0185,-.013928,
.019642,-.013128,
.020628,-.012142,
.021428,-.011,
.022018,-.009736,
.022378,-.008389,
.0225,-.007,
.0225,.007,
.022378,.008389,
.022018,.009736,
.021428,.011,
.020628,.012142,
.019642,.013128,
.0185,.013928,
.017236,.014518,
.015889,.014878,
.0145,.015,
-.0145,.015,
-.015889,.014878,
-.017236,.014518,
-.0185,.013928,
-.019642,.013128,
-.020628,.012142,
-.021428,.011,
-.022018,.009736,
-.022378,.008389,
-.0225,.007,
-.0225,-.007,
0.0*
%
%ADD55MACRO55*%
%AMMACRO52*
4,1,40,-.007,.0225,
-.008389,.022378,
-.009736,.022018,
-.011,.021428,
-.012142,.020628,
-.013128,.019642,
-.013928,.0185,
-.014518,.017236,
-.014878,.015889,
-.015,.0145,
-.015,-.0145,
-.014878,-.015889,
-.014518,-.017236,
-.013928,-.0185,
-.013128,-.019642,
-.012142,-.020628,
-.011,-.021428,
-.009736,-.022018,
-.008389,-.022378,
-.007,-.0225,
.007,-.0225,
.008389,-.022378,
.009736,-.022018,
.011,-.021428,
.012142,-.020628,
.013128,-.019642,
.013928,-.0185,
.014518,-.017236,
.014878,-.015889,
.015,-.0145,
.015,.0145,
.014878,.015889,
.014518,.017236,
.013928,.0185,
.013128,.019642,
.012142,.020628,
.011,.021428,
.009736,.022018,
.008389,.022378,
.007,.0225,
-.007,.0225,
0.0*
%
%ADD52MACRO52*%
%AMMACRO30*
4,1,40,.012,.008,
.012,-.008,
.011939,-.008695,
.011759,-.009368,
.011464,-.01,
.011064,-.010571,
.010571,-.011064,
.01,-.011464,
.009368,-.011759,
.008695,-.011939,
.008,-.012,
-.008,-.012,
-.008695,-.011939,
-.009368,-.011759,
-.01,-.011464,
-.010571,-.011064,
-.011064,-.010571,
-.011464,-.01,
-.011759,-.009368,
-.011939,-.008695,
-.012,-.008,
-.012,.008,
-.011939,.008695,
-.011759,.009368,
-.011464,.01,
-.011064,.010571,
-.010571,.011064,
-.01,.011464,
-.009368,.011759,
-.008695,.011939,
-.008,.012,
.008,.012,
.008695,.011939,
.009368,.011759,
.01,.011464,
.010571,.011064,
.011064,.010571,
.011464,.01,
.011759,.009368,
.011939,.008695,
.012,.008,
0.0*
%
%ADD30MACRO30*%
%AMMACRO20*
4,1,40,.008,-.012,
-.008,-.012,
-.008695,-.011939,
-.009368,-.011759,
-.01,-.011464,
-.010571,-.011064,
-.011064,-.010571,
-.011464,-.01,
-.011759,-.009368,
-.011939,-.008695,
-.012,-.008,
-.012,.008,
-.011939,.008695,
-.011759,.009368,
-.011464,.01,
-.011064,.010571,
-.010571,.011064,
-.01,.011464,
-.009368,.011759,
-.008695,.011939,
-.008,.012,
.008,.012,
.008695,.011939,
.009368,.011759,
.01,.011464,
.010571,.011064,
.011064,.010571,
.011464,.01,
.011759,.009368,
.011939,.008695,
.012,.008,
.012,-.008,
.011939,-.008695,
.011759,-.009368,
.011464,-.01,
.011064,-.010571,
.010571,-.011064,
.01,-.011464,
.009368,-.011759,
.008695,-.011939,
.008,-.012,
0.0*
%
%ADD20MACRO20*%
%AMMACRO17*
4,1,40,-.007,.011,
.007,.011,
.007695,.010939,
.008368,.010759,
.009,.010464,
.009571,.010064,
.010064,.009571,
.010464,.009,
.010759,.008368,
.010939,.007695,
.011,.007,
.011,-.007,
.010939,-.007695,
.010759,-.008368,
.010464,-.009,
.010064,-.009571,
.009571,-.010064,
.009,-.010464,
.008368,-.010759,
.007695,-.010939,
.007,-.011,
-.007,-.011,
-.007695,-.010939,
-.008368,-.010759,
-.009,-.010464,
-.009571,-.010064,
-.010064,-.009571,
-.010464,-.009,
-.010759,-.008368,
-.010939,-.007695,
-.011,-.007,
-.011,.007,
-.010939,.007695,
-.010759,.008368,
-.010464,.009,
-.010064,.009571,
-.009571,.010064,
-.009,.010464,
-.008368,.010759,
-.007695,.010939,
-.007,.011,
0.0*
%
%ADD17MACRO17*%
%AMMACRO31*
4,1,40,.011,.007,
.011,-.007,
.010939,-.007695,
.010759,-.008368,
.010464,-.009,
.010064,-.009571,
.009571,-.010064,
.009,-.010464,
.008368,-.010759,
.007695,-.010939,
.007,-.011,
-.007,-.011,
-.007695,-.010939,
-.008368,-.010759,
-.009,-.010464,
-.009571,-.010064,
-.010064,-.009571,
-.010464,-.009,
-.010759,-.008368,
-.010939,-.007695,
-.011,-.007,
-.011,.007,
-.010939,.007695,
-.010759,.008368,
-.010464,.009,
-.010064,.009571,
-.009571,.010064,
-.009,.010464,
-.008368,.010759,
-.007695,.010939,
-.007,.011,
.007,.011,
.007695,.010939,
.008368,.010759,
.009,.010464,
.009571,.010064,
.010064,.009571,
.010464,.009,
.010759,.008368,
.010939,.007695,
.011,.007,
0.0*
%
%ADD31MACRO31*%
%AMMACRO71*
4,1,6,-.0135,-.025,
.0065,-.005,
.0135,-.005,
.0135,.005,
.0065,.005,
-.0135,.025,
-.0135,-.025,
0.0*
%
%ADD71MACRO71*%
%AMMACRO25*
4,1,40,.013,-.017,
-.013,-.017,
-.013695,-.016939,
-.014368,-.016759,
-.015,-.016464,
-.015571,-.016064,
-.016064,-.015571,
-.016464,-.015,
-.016759,-.014368,
-.016939,-.013695,
-.017,-.013,
-.017,.013,
-.016939,.013695,
-.016759,.014368,
-.016464,.015,
-.016064,.015571,
-.015571,.016064,
-.015,.016464,
-.014368,.016759,
-.013695,.016939,
-.013,.017,
.013,.017,
.013695,.016939,
.014368,.016759,
.015,.016464,
.015571,.016064,
.016064,.015571,
.016464,.015,
.016759,.014368,
.016939,.013695,
.017,.013,
.017,-.013,
.016939,-.013695,
.016759,-.014368,
.016464,-.015,
.016064,-.015571,
.015571,-.016064,
.015,-.016464,
.014368,-.016759,
.013695,-.016939,
.013,-.017,
0.0*
%
%ADD25MACRO25*%
%AMMACRO23*
4,1,40,-.017,-.013,
-.017,.013,
-.016939,.013695,
-.016759,.014368,
-.016464,.015,
-.016064,.015571,
-.015571,.016064,
-.015,.016464,
-.014368,.016759,
-.013695,.016939,
-.013,.017,
.013,.017,
.013695,.016939,
.014368,.016759,
.015,.016464,
.015571,.016064,
.016064,.015571,
.016464,.015,
.016759,.014368,
.016939,.013695,
.017,.013,
.017,-.013,
.016939,-.013695,
.016759,-.014368,
.016464,-.015,
.016064,-.015571,
.015571,-.016064,
.015,-.016464,
.014368,-.016759,
.013695,-.016939,
.013,-.017,
-.013,-.017,
-.013695,-.016939,
-.014368,-.016759,
-.015,-.016464,
-.015571,-.016064,
-.016064,-.015571,
-.016464,-.015,
-.016759,-.014368,
-.016939,-.013695,
-.017,-.013,
0.0*
%
%ADD23MACRO23*%
%AMMACRO29*
4,1,40,.012,.008,
.012,-.008,
.011939,-.008695,
.011759,-.009368,
.011464,-.01,
.011064,-.010571,
.010571,-.011064,
.01,-.011464,
.009368,-.011759,
.008695,-.011939,
.008,-.012,
-.008,-.012,
-.008695,-.011939,
-.009368,-.011759,
-.01,-.011464,
-.010571,-.011064,
-.011064,-.010571,
-.011464,-.01,
-.011759,-.009368,
-.011939,-.008695,
-.012,-.008,
-.012,.008,
-.011939,.008695,
-.011759,.009368,
-.011464,.01,
-.011064,.010571,
-.010571,.011064,
-.01,.011464,
-.009368,.011759,
-.008695,.011939,
-.008,.012,
.008,.012,
.008695,.011939,
.009368,.011759,
.01,.011464,
.010571,.011064,
.011064,.010571,
.011464,.01,
.011759,.009368,
.011939,.008695,
.012,.008,
0.0*
%
%ADD29MACRO29*%
%AMMACRO19*
4,1,40,.008,-.012,
-.008,-.012,
-.008695,-.011939,
-.009368,-.011759,
-.01,-.011464,
-.010571,-.011064,
-.011064,-.010571,
-.011464,-.01,
-.011759,-.009368,
-.011939,-.008695,
-.012,-.008,
-.012,.008,
-.011939,.008695,
-.011759,.009368,
-.011464,.01,
-.011064,.010571,
-.010571,.011064,
-.01,.011464,
-.009368,.011759,
-.008695,.011939,
-.008,.012,
.008,.012,
.008695,.011939,
.009368,.011759,
.01,.011464,
.010571,.011064,
.011064,.010571,
.011464,.01,
.011759,.009368,
.011939,.008695,
.012,.008,
.012,-.008,
.011939,-.008695,
.011759,-.009368,
.011464,-.01,
.011064,-.010571,
.010571,-.011064,
.01,-.011464,
.009368,-.011759,
.008695,-.011939,
.008,-.012,
0.0*
%
%ADD19MACRO19*%
%AMMACRO18*
4,1,40,-.007,.011,
.007,.011,
.007695,.010939,
.008368,.010759,
.009,.010464,
.009571,.010064,
.010064,.009571,
.010464,.009,
.010759,.008368,
.010939,.007695,
.011,.007,
.011,-.007,
.010939,-.007695,
.010759,-.008368,
.010464,-.009,
.010064,-.009571,
.009571,-.010064,
.009,-.010464,
.008368,-.010759,
.007695,-.010939,
.007,-.011,
-.007,-.011,
-.007695,-.010939,
-.008368,-.010759,
-.009,-.010464,
-.009571,-.010064,
-.010064,-.009571,
-.010464,-.009,
-.010759,-.008368,
-.010939,-.007695,
-.011,-.007,
-.011,.007,
-.010939,.007695,
-.010759,.008368,
-.010464,.009,
-.010064,.009571,
-.009571,.010064,
-.009,.010464,
-.008368,.010759,
-.007695,.010939,
-.007,.011,
0.0*
%
%ADD18MACRO18*%
%ADD75C,.012*%
%ADD76C,.013*%
%ADD77C,.014*%
%ADD78C,.015*%
%ADD79C,.016*%
%ADD80C,.004*%
%ADD81C,.005*%
%ADD82C,.006*%
%ADD83C,.007*%
%ADD84C,.008*%
%ADD85C,.0035*%
%ADD86C,.0049*%
%ADD87C,.00375*%
%ADD88C,.00538*%
%ADD89C,.00575*%
%ADD105R,.016X.008*%
%ADD101R,.008X.016*%
%ADD93C,.03004*%
%ADD106R,.018X.008*%
%ADD102R,.008X.018*%
%ADD98O,.08402X.13502*%
%ADD97O,.08402X.10802*%
%ADD100R,.008X.019*%
%ADD94R,.019X.008*%
%ADD104R,.008X.0182*%
%ADD107R,.008X.0165*%
%ADD92C,.04404*%
%ADD103R,.008X.0185*%
%ADD95C,.02804*%
%ADD96C,.07404*%
%ADD99C,.06604*%
%ADD91C,.04804*%
%ADD90R,.008X.008*%
G75*
%LPD*%
G75*
G36*
G01X26483Y752780D02*
X11125Y722062D01*
X10896D01*
X10750Y721916D01*
Y721708D01*
X10896Y721562D01*
X11000D01*
Y11000D01*
X109197D01*
Y40396D01*
X109343Y40437D01*
G03Y48147I-1075J3855D01*
G01X109197Y48188D01*
Y429336D01*
G02X109478Y432217I14937J-3D01*
G01X117226D01*
G02X117603Y431682I0J-400D01*
G03X117193Y429333I6531J-2350D01*
G01Y3937D01*
G02X116260Y3004I-933J0D01*
G01X3937D01*
G02X3004Y3937I0J933D01*
G01Y723480D01*
G02X3103Y723897I933J-1D01*
G01X21284Y760260D01*
G02X22118Y760776I835J-417D01*
G01X386150D01*
G02X386984Y760260I-1J-933D01*
G01X405165Y723897D01*
G02X405264Y723480I-834J-418D01*
G01Y722062D01*
X397143D01*
X381785Y752780D01*
X379625D01*
X379565Y752853D01*
G03X348722Y752780I-15392J-12696D01*
G01X64664D01*
G03X33762I-15451J-12623D01*
G01X26483D01*
G37*
G36*
G01X120010Y558132D02*
G02X120408Y557693I0J-400D01*
G03X124792I2192J-213D01*
G02X125190Y558132I398J39D01*
G01X129957D01*
X134141Y562316D01*
X152685D01*
X153047Y561954D01*
X154102D01*
X154234Y562086D01*
X158000D01*
Y554782D01*
X155818Y552600D01*
X141574D01*
X140958Y551984D01*
Y549958D01*
X140900Y549900D01*
X130299D01*
X125064Y544665D01*
Y540664D01*
X117600Y533200D01*
Y524900D01*
X116000Y523300D01*
Y504300D01*
X113348Y501648D01*
X112617D01*
X112578Y501652D01*
X104069D01*
X103617Y501200D01*
X103450D01*
X100602Y498352D01*
X61849D01*
X61797Y498300D01*
X38831D01*
X27525Y509606D01*
Y576986D01*
X42086Y591547D01*
X49020D01*
X50398Y590168D01*
Y582902D01*
X50648Y582652D01*
Y582398D01*
X50902D01*
X50953Y582348D01*
Y574783D01*
X51894Y573842D01*
Y572849D01*
X51890Y572829D01*
G03X51854Y572495I1566J-338D01*
G01Y571095D01*
G03X51859Y570982I1601J14D01*
G01Y570728D01*
X51339Y570208D01*
X48942D01*
X48932Y570209D01*
G03X48768Y570218I-170J-1593D01*
G01X46168D01*
G03X46004Y570209I6J-1602D01*
G01X45994Y570208D01*
X44920D01*
X44198Y569486D01*
Y566047D01*
X42001Y563850D01*
X40213D01*
X39514Y563151D01*
Y561823D01*
X39512Y561810D01*
G03X39498Y561600I1588J-211D01*
G01Y560200D01*
G03X39512Y559990I1602J1D01*
G01X39514Y559977D01*
Y539380D01*
X39508Y539355D01*
G03X39456Y538954I1550J-405D01*
G01Y537554D01*
G03X39508Y537153I1602J4D01*
G01X39514Y537128D01*
Y516657D01*
X48571Y507600D01*
X63271D01*
X63288Y507597D01*
G03X63551Y507576I259J1580D01*
G01X64951D01*
G03X65214Y507597I4J1601D01*
G01X65231Y507600D01*
X68558D01*
X68593Y507586D01*
G03X69175Y507476I583J1491D01*
G01X70581D01*
G03X71163Y507586I-1J1601D01*
G01X71198Y507600D01*
X74405D01*
X74421Y507598D01*
G03X74673Y507578I252J1581D01*
G01X76073D01*
G03X76325Y507598I0J1601D01*
G01X76341Y507600D01*
X80032D01*
X80052Y507596D01*
G03X80368Y507564I319J1570D01*
G01X81768D01*
G03X82084Y507596I-3J1602D01*
G01X82104Y507600D01*
X98900D01*
X99068Y507768D01*
X99112Y507783D01*
G03X100117Y508788I-512J1517D01*
G01X100132Y508832D01*
X100300Y509000D01*
Y509087D01*
X103700Y512487D01*
Y554160D01*
X103705Y554182D01*
G03X103746Y554540I-1561J360D01*
G01Y555940D01*
G03X103705Y556298I-1602J-2D01*
G01X103700Y556320D01*
Y557261D01*
X102715Y558246D01*
X101398D01*
X100428Y559216D01*
Y561713D01*
X99601Y562540D01*
X97040D01*
X96894Y562394D01*
X96851Y562379D01*
G03X96550Y562238I525J-1513D01*
G01X92257D01*
X91812Y562683D01*
X90395D01*
X90365Y562693D01*
G03X89404Y562683I-466J-1428D01*
G01X89354D01*
X88912Y563125D01*
Y565108D01*
X89402Y565598D01*
X96100D01*
G03X96310Y565584I211J1588D01*
G01X97916D01*
G03X98126Y565598I-1J1602D01*
G01X99603D01*
G03X99817Y565584I211J1587D01*
G01X101421D01*
G03X101635Y565598I3J1601D01*
G01X109630D01*
X117097Y558132D01*
X120010D01*
G37*
G36*
G01X77376Y564739D02*
X77035Y565080D01*
Y568659D01*
X76270Y569424D01*
X74780D01*
X74778Y569426D01*
X70746D01*
X69922Y570250D01*
Y577492D01*
X70590Y578160D01*
X71520D01*
X72100Y577580D01*
Y576210D01*
X72610Y575700D01*
X73421D01*
X73464Y575678D01*
G03X74840I688J1335D01*
G01X74883Y575700D01*
X78302D01*
X79476Y574526D01*
Y565005D01*
X79210Y564739D01*
X77376D01*
G37*
G36*
G01X68900Y576300D02*
X67965Y575365D01*
X67880Y575367D01*
G03X66390Y574205I-27J-1502D01*
G01X66354Y574050D01*
X57800D01*
X57550Y574300D01*
Y577450D01*
X56725Y578275D01*
X53275D01*
X52425Y579125D01*
Y582575D01*
X51600Y583400D01*
Y590500D01*
X52850Y591750D01*
X58600D01*
X62200Y588150D01*
Y584102D01*
X62191Y584072D01*
G03X62148Y583800I859J-275D01*
G01Y581200D01*
G03X62191Y580928I902J3D01*
G01X62200Y580898D01*
Y580650D01*
X62900Y579950D01*
X67650D01*
X68900Y578700D01*
Y576300D01*
G37*
G36*
G01X72052Y659452D02*
X59400D01*
Y672291D01*
X72052D01*
Y659452D01*
G37*
G36*
G01X128050Y506650D02*
X126100Y508600D01*
X117250Y517449D01*
Y522900D01*
X118800Y524450D01*
X118776Y524474D01*
Y528850D01*
X122076Y532150D01*
X124000D01*
X125700Y533850D01*
Y537099D01*
X134738Y546137D01*
Y547662D01*
X135372Y548296D01*
X141197D01*
X142200Y549299D01*
Y550905D01*
X142842Y551547D01*
X154752D01*
X155700Y550599D01*
Y547099D01*
X155442Y546841D01*
X149415D01*
X145524Y542950D01*
X144200D01*
X142200Y540950D01*
Y529752D01*
G03Y528248I1300J-752D01*
G01Y522550D01*
X148950Y515800D01*
Y509250D01*
X146999Y507299D01*
X138904D01*
Y509422D01*
X136569Y511757D01*
G03X133455Y508643I-1557J-1557D01*
G01X134500Y507598D01*
Y506650D01*
X128050D01*
G37*
G36*
G01X123254Y586204D02*
X135280Y574179D01*
X146220D01*
X147000Y573399D01*
X149626D01*
X150585Y572440D01*
Y569018D01*
X151006Y568597D01*
X153629D01*
X153900Y568326D01*
Y564399D01*
X153500Y563999D01*
X131939D01*
X127703Y559763D01*
X118205D01*
X111167Y566801D01*
X89134D01*
X88839Y567096D01*
Y568374D01*
X88217Y568996D01*
X87207D01*
X87179Y569004D01*
G03X86321I-429J-1439D01*
G01X86293Y568996D01*
X84939D01*
X84710Y568767D01*
Y567030D01*
X84284Y566604D01*
X82500D01*
X82325Y566779D01*
Y570280D01*
X84444Y572399D01*
X86418D01*
X86439Y572395D01*
G03X87061I311J1469D01*
G01X87082Y572399D01*
X89567D01*
X89588Y572395D01*
G03X90210I311J1469D01*
G01X90231Y572399D01*
X90898D01*
X92649Y574150D01*
X98773D01*
X98805Y574139D01*
G03X99330Y574050I526J1513D01*
G01X100930D01*
G03X101455Y574139I-1J1602D01*
G01X101487Y574150D01*
X101951D01*
X102526Y574725D01*
Y575519D01*
X102527Y575527D01*
G03X102532Y575652I-1597J126D01*
G01Y577252D01*
G03X102527Y577377I-1602J-1D01*
G01X102526Y577385D01*
Y578421D01*
X101687Y579260D01*
X92384D01*
X91827Y579817D01*
Y588239D01*
X91853Y588265D01*
Y591553D01*
X92882Y592582D01*
X104232D01*
X110610Y586204D01*
X123254D01*
G37*
G36*
G01X140980Y613356D02*
G03X140978Y610073I1467J-1642D01*
G01Y603450D01*
X140988Y603440D01*
Y603259D01*
X140990Y603257D01*
Y603060D01*
X143115Y600935D01*
Y594665D01*
X142900Y594450D01*
X127950D01*
X127350Y595050D01*
Y598570D01*
X129300Y600520D01*
X134270D01*
X135477Y601727D01*
X135518Y601742D01*
G03X136958Y603182I-818J2258D01*
G01X136973Y603223D01*
X137250Y603500D01*
Y605450D01*
X133810Y608890D01*
X131030D01*
X131020Y608891D01*
G03X130570Y608890I-220J-2191D01*
G01X130540D01*
X130095Y609335D01*
Y613856D01*
X130096Y613864D01*
G03X130102Y614000I-1596J139D01*
G01Y615400D01*
G03X130096Y615536I-1602J-3D01*
G01X130095Y615544D01*
Y616305D01*
X129400Y617000D01*
X128565D01*
G03X128500Y617002I-82J-1599D01*
G01X127100D01*
G03X127035Y617000I17J-1601D01*
G01X126150D01*
X124510Y615360D01*
X124314D01*
X124283Y615371D01*
G03X122717I-783J-2271D01*
G01X122686Y615360D01*
X121750D01*
X120950Y616160D01*
Y618810D01*
X125620Y623480D01*
X139902D01*
G03X140900Y622550I2069J1220D01*
G01X140980Y622470D01*
Y613356D01*
G37*
G36*
G01X126842Y604800D02*
X126866Y604794D01*
G03X127480Y604729I537J2136D01*
G01X127567Y604733D01*
X128110Y604190D01*
Y601055D01*
X126102Y599048D01*
Y595502D01*
X125300Y594700D01*
X115600D01*
X115350Y594950D01*
Y598450D01*
X116721Y599821D01*
X116816Y599810D01*
G03X118400Y603740I234J2190D01*
G01Y607077D01*
X118402Y607091D01*
G03X118424Y607347I-2379J333D01*
G01X118426Y607426D01*
X118800Y607800D01*
X123900D01*
X124500Y607200D01*
Y606520D01*
X126220Y604800D01*
X126842D01*
G37*
G36*
G01X253586Y656232D02*
X249617Y660202D01*
X248976D01*
X248453Y660725D01*
X232986D01*
G03X230014I-1486J-1625D01*
G01X216447D01*
X216305Y660583D01*
X216242Y660573D01*
G03X214692Y659500I358J-2173D01*
G01X211800D01*
X210202Y657902D01*
X192851D01*
X190700Y655750D01*
X183650D01*
X183646Y655746D01*
X177603D01*
X177498Y655642D01*
X177364D01*
X169848Y648126D01*
X169783D01*
X169781Y648124D01*
X127844D01*
X122034Y653934D01*
X120759Y655208D01*
X120600Y655367D01*
Y668400D01*
X122100Y669900D01*
X141043D01*
X156543Y654400D01*
X169216D01*
X185510Y670694D01*
X188013D01*
X188047Y670536D01*
G03X192355Y670549I2153J464D01*
G01X192389Y670708D01*
X227439D01*
X232434Y665714D01*
X247716D01*
X248101Y666098D01*
X252580D01*
X259109Y659570D01*
X273933D01*
X290500Y676137D01*
X306486D01*
X307192Y675431D01*
Y671800D01*
X306900Y671508D01*
Y671500D01*
X305808Y670408D01*
X305679Y670472D01*
G03X302505Y668675I-979J-1972D01*
G01X302499Y668602D01*
X300598Y666701D01*
Y665198D01*
X288101Y652701D01*
X257117D01*
X255986Y653832D01*
X255984Y653911D01*
G03X253665Y656230I-2401J-82D01*
G01X253586Y656232D01*
G37*
G36*
G01X94200Y701600D02*
X85000D01*
X83500Y703100D01*
Y708600D01*
X84900Y710000D01*
X93500D01*
X95100Y708400D01*
Y702500D01*
X94200Y701600D01*
G37*
G36*
G01X128500Y704548D02*
Y725800D01*
X141600D01*
Y703900D01*
X129148D01*
X128500Y704548D01*
G37*
G36*
G01X223600Y514602D02*
G03X221400Y512485I0J-2202D01*
G02X221000Y512100I-400J15D01*
G01X203200D01*
X202400Y512900D01*
Y515400D01*
X201800Y516000D01*
X194953D01*
X193000Y517953D01*
Y519382D01*
G03Y519680I-2397J149D01*
G01Y519875D01*
X193176Y520052D01*
Y521076D01*
X193299Y521198D01*
X222802D01*
X224000Y520000D01*
Y515002D01*
G02X223600Y514602I-400J0D01*
G37*
G36*
G01X163400Y518198D02*
G03X163648Y518218I-4J1602D01*
G01X163748Y518234D01*
X164161Y517821D01*
Y516264D01*
X163240Y515343D01*
X161901D01*
X159059Y512501D01*
X154697D01*
X153936Y513262D01*
Y514560D01*
X154753Y515377D01*
X154823Y515384D01*
G03X156251Y516812I-165J1593D01*
G01X156258Y516882D01*
X156666Y517290D01*
Y525870D01*
X158266Y527470D01*
X161229D01*
X162605Y528846D01*
X164474D01*
X164765Y528555D01*
Y526540D01*
X163995Y525770D01*
X161813D01*
X160648Y524605D01*
Y522058D01*
G03X160398Y521200I1352J-859D01*
G01Y519800D01*
G03X160620Y518987I1602J1D01*
G01X160648Y518940D01*
Y518811D01*
X161163Y518296D01*
X161449D01*
X161480Y518285D01*
G03X162000Y518198I521J1515D01*
G01X163400D01*
G37*
G36*
G01X172506Y523175D02*
Y519143D01*
G03X171598Y517700I693J-1443D01*
G01Y516300D01*
G03X172506Y514857I1601J0D01*
G01Y514088D01*
X172505Y514080D01*
G03X172502Y513767I2195J-178D01*
G01X172507Y513677D01*
X171321Y512491D01*
X165884D01*
X165526Y512849D01*
Y513523D01*
X166798Y514795D01*
X168636D01*
X169329Y515488D01*
Y522884D01*
X170168Y523723D01*
X171958D01*
X172506Y523175D01*
G37*
G36*
G01X181801Y521441D02*
X183808Y519434D01*
X183814Y519360D01*
G03X183944Y518838I1597J121D01*
G01X183961Y518800D01*
Y518162D01*
X183944Y518124D01*
G03X183810Y517481I1467J-641D01*
G01Y516081D01*
G03X183944Y515438I1601J-2D01*
G01X183961Y515400D01*
Y512816D01*
X183468Y512323D01*
X178636D01*
X178352Y512608D01*
Y514544D01*
X178637Y514830D01*
X178670Y514845D01*
G03X179455Y515630I-670J1455D01*
G01X179470Y515663D01*
X179600Y515793D01*
Y516235D01*
G03X179602Y516300I-1599J82D01*
G01Y517700D01*
G03X179600Y517765I-1601J-17D01*
G01Y518750D01*
X178225Y520125D01*
Y523160D01*
X177309Y524076D01*
X177305Y524153D01*
G03X175885Y525573I-1500J-80D01*
G01X175808Y525577D01*
X173401Y527984D01*
Y533331D01*
X173648Y533578D01*
X175348D01*
X175684Y533242D01*
Y530141D01*
X176164Y529661D01*
Y528376D01*
X178021Y526519D01*
X179967D01*
X180773Y525713D01*
Y524755D01*
X180750Y524711D01*
G03X181801Y521441I2124J-1121D01*
G37*
G36*
G01X191776Y530800D02*
X193500Y529076D01*
Y528700D01*
X194800Y527400D01*
X216400D01*
X217300Y528300D01*
X223100D01*
Y522900D01*
X222600Y522400D01*
X215465D01*
G03X215400Y522402I-82J-1599D01*
G01X212800D01*
G03X212735Y522400I17J-1601D01*
G01X196765D01*
G03X196700Y522402I-82J-1599D01*
G01X194100D01*
G03X194082Y522401I80J-1598D01*
G02X193884Y522641I-2J200D01*
G03X189535Y522842I-2159J433D01*
G02X189138Y522400I-398J-42D01*
G01X187500D01*
X187000Y522900D01*
Y529600D01*
X188200Y530800D01*
X191776D01*
G37*
G36*
G01X171739Y572762D02*
X170198Y574303D01*
X168100D01*
X167825Y574578D01*
Y575785D01*
X168027Y575987D01*
X168138D01*
G03X169613Y575959I760J1178D01*
G01X169660Y575987D01*
X169711D01*
X170335Y576611D01*
Y588039D01*
X170601Y588305D01*
X173449D01*
X173633Y588121D01*
Y573072D01*
X173323Y572762D01*
X171739D01*
G37*
G36*
G01X187610Y556710D02*
X187350Y556450D01*
X187309Y556435D01*
G03X186487Y554616I486J-1315D01*
G01X186500Y554582D01*
Y554400D01*
X187300Y553600D01*
Y550550D01*
X187000Y550250D01*
X183300D01*
X182950Y550600D01*
Y555875D01*
X182175Y556650D01*
Y563170D01*
X183077Y564072D01*
Y565632D01*
X182595Y566114D01*
X179488D01*
X178855Y566747D01*
Y569555D01*
X178967Y569610D01*
G03Y572126I-620J1258D01*
G01X178855Y572181D01*
Y572524D01*
X179770Y573439D01*
Y577589D01*
X180380Y578199D01*
X188370D01*
X189980Y579809D01*
Y584459D01*
X190330Y584809D01*
X197466D01*
X198114Y584161D01*
Y581216D01*
X197530Y580632D01*
Y575815D01*
X199022Y574323D01*
X199007Y574223D01*
G03X199873Y572714I1387J-207D01*
G01X199999Y572664D01*
Y572218D01*
X199873Y572168D01*
G03Y569564I521J-1302D01*
G01X199999Y569514D01*
Y567136D01*
X198651Y565788D01*
X195829D01*
X195180Y565139D01*
Y562082D01*
X194520Y561422D01*
X192550D01*
X191990Y560862D01*
Y557435D01*
X191265Y556710D01*
X187610D01*
G37*
G36*
G01X176628Y578686D02*
X174529D01*
X174167Y579048D01*
Y588296D01*
X173633Y588830D01*
X168208D01*
X167743Y589295D01*
Y590147D01*
X168079Y590483D01*
X176439D01*
X176801Y590121D01*
Y578859D01*
X176628Y578686D01*
G37*
G36*
G01X198131Y557499D02*
G03X198252Y557950I-780J451D01*
G01Y560550D01*
G03X198251Y560570I-900J-35D01*
G02X198651Y560979I400J9D01*
G01X202205D01*
X202257Y560859D01*
G03X204906Y561748I1286J558D01*
G01X204900Y561771D01*
Y564215D01*
X204906Y564238D01*
G03Y564898I-1363J330D01*
G01X204900Y564921D01*
Y567829D01*
X206070Y568999D01*
X207427D01*
X207446Y568995D01*
G03X207667Y568964I374J1865D01*
G01X207741Y568958D01*
X208515Y568184D01*
X208486Y568073D01*
G03X208493Y567337I1356J-355D01*
G01X208500Y567310D01*
Y564974D01*
X208493Y564947D01*
G03Y564187I1349J-380D01*
G01X208500Y564160D01*
Y561824D01*
X208493Y561797D01*
G03Y561037I1349J-380D01*
G01X208500Y561010D01*
Y558675D01*
X208493Y558648D01*
G03X208441Y558228I1349J-380D01*
G01X208443Y558142D01*
X207200Y556899D01*
X198477D01*
G02X198131Y557499I0J400D01*
G37*
G36*
G01X202936Y585349D02*
X202975Y585332D01*
G03X203770Y585231I567J1282D01*
G01X203872Y585247D01*
X204360Y584759D01*
Y582469D01*
X203710Y581819D01*
X202880D01*
X202090Y581029D01*
Y579692D01*
X204830Y576952D01*
Y573609D01*
X204150Y572929D01*
X202060D01*
G02X201690Y573481I0J400D01*
G03X199529Y575119I-1296J535D01*
G01X199389Y575010D01*
X198193Y576206D01*
Y580192D01*
X199910Y581909D01*
Y584389D01*
X200789Y585268D01*
X200834Y585283D01*
G03X200960Y585332I-445J1330D01*
G01X200999Y585349D01*
X202936D01*
G37*
G36*
G01X177895Y578699D02*
X177503Y579091D01*
Y587302D01*
X178300Y588099D01*
X181200D01*
X184300Y584999D01*
X188550D01*
X188820Y584729D01*
Y579569D01*
X187952Y578700D01*
X180172D01*
X180171Y578699D01*
X177895D01*
G37*
G36*
G01X184309Y597851D02*
X185890Y596270D01*
X187157D01*
X187159Y596268D01*
X187360D01*
X188406Y595222D01*
Y595021D01*
X189709Y593718D01*
X191772D01*
X191990Y593500D01*
Y588940D01*
X191500Y588450D01*
X188300D01*
X185500Y591250D01*
X183840D01*
X182910Y592180D01*
Y596770D01*
X182080Y597600D01*
X181320D01*
X180780Y598140D01*
Y603850D01*
X178750Y605880D01*
X178470D01*
X177920Y606430D01*
Y617010D01*
X176080Y618850D01*
Y624331D01*
G02X176606Y624710I400J0D01*
G03X178596Y625020I694J2090D01*
G01X180740D01*
X181255Y624505D01*
Y618035D01*
X182260Y617030D01*
Y606120D01*
X182890Y605490D01*
Y603722D01*
X182886Y603704D01*
G03Y602804I2360J-450D01*
G01X182890Y602786D01*
Y599270D01*
X183283Y598877D01*
X183297Y598827D01*
G03X184259Y597865I1348J386D01*
G01X184309Y597851D01*
G37*
G36*
G01X169050Y611158D02*
Y617280D01*
X169080Y617310D01*
X175930D01*
X176300Y616940D01*
Y616400D01*
X176230Y616330D01*
Y613220D01*
X176970Y612480D01*
Y606540D01*
X176630Y606200D01*
X173448D01*
X170314Y609334D01*
Y609894D01*
X169050Y611158D01*
G37*
G36*
G01X186820Y609800D02*
X186170Y610450D01*
Y612140D01*
X188050Y614020D01*
X188660D01*
X189090Y614450D01*
Y624600D01*
X189740Y625250D01*
X194320D01*
X194880Y624690D01*
Y623562D01*
X194414Y623096D01*
Y618467D01*
X193648Y617701D01*
Y616161D01*
X192108Y614621D01*
Y610558D01*
X191350Y609800D01*
X186820D01*
G37*
G36*
G01X166498Y613710D02*
X164930Y615279D01*
Y617536D01*
X164880Y617586D01*
Y617870D01*
X164250Y618500D01*
Y624250D01*
X165110Y625110D01*
X172850D01*
X173250Y624710D01*
Y618950D01*
X172875Y618575D01*
X168325D01*
X167850Y618100D01*
Y614030D01*
X167530Y613710D01*
X166498D01*
G37*
G36*
G01X211530Y603620D02*
X210800Y604350D01*
X210742D01*
Y609267D01*
X216475Y615000D01*
X216800D01*
X217745Y615945D01*
Y616270D01*
X217746Y616272D01*
Y617192D01*
X218162Y617608D01*
Y618090D01*
X222110D01*
X222500Y617700D01*
Y612430D01*
X221910Y611840D01*
X221400D01*
X221390Y611830D01*
X220230D01*
X220000Y611600D01*
Y611580D01*
X218940Y610520D01*
Y607800D01*
X218060Y606920D01*
X217750D01*
X217330Y606500D01*
Y604050D01*
X216900Y603620D01*
X213614D01*
X213575Y603638D01*
G03X212409I-583J-1275D01*
G01X212370Y603620D01*
X211530D01*
G37*
G36*
G01X258555Y627400D02*
X255687Y624532D01*
X255611Y624528D01*
G03X253629Y622979I122J-2199D01*
G01X253586Y622838D01*
X251870D01*
G03X251541Y622804I-1J-1601D01*
G01X251520Y622800D01*
X249850D01*
X248830Y623820D01*
X243780D01*
X243570Y624030D01*
Y630470D01*
X245384Y632284D01*
X257311D01*
X258555Y631040D01*
Y627400D01*
G37*
G36*
G01X218600Y603700D02*
X218050Y604250D01*
Y606220D01*
X218248Y606418D01*
X218268D01*
X218389Y606540D01*
X219860D01*
X220620Y607300D01*
Y610790D01*
X220990Y611160D01*
X224360D01*
X224970Y610550D01*
Y606443D01*
X222227Y603700D01*
X218600D01*
G37*
G36*
G01X220430Y631077D02*
X221139Y631786D01*
X222819D01*
G03X223005Y631797I-1J1602D01*
G01X223101Y631809D01*
X223340Y631570D01*
Y628960D01*
X224100Y628200D01*
X226400D01*
X226982Y628782D01*
X227005Y628795D01*
G03X227488Y629175I-1107J1904D01*
G01X228225D01*
X228290Y629240D01*
X229800D01*
X229830Y629270D01*
X230570D01*
X231300Y630000D01*
X234475D01*
X234775Y629700D01*
Y627500D01*
X234312Y627038D01*
X232588D01*
X231400Y625850D01*
X227715D01*
X226566Y624702D01*
X226102D01*
X225986Y624585D01*
X220855D01*
X220430Y625010D01*
Y631077D01*
G37*
G36*
G01X232520Y615030D02*
X231930Y614440D01*
X231868Y614429D01*
G03X230651Y613212I262J-1479D01*
G01X230640Y613150D01*
X229670Y612180D01*
X225160D01*
X224910Y612430D01*
Y618140D01*
X225340Y618570D01*
X233110D01*
X236060Y621520D01*
X250660D01*
X250738Y621598D01*
X253651D01*
X253703Y621476D01*
G03X255082Y620225I2030J853D01*
G01X255129Y620211D01*
X255240Y620100D01*
X260290D01*
X261220Y619170D01*
Y616220D01*
X260880Y615880D01*
X250426D01*
X250397Y615889D01*
G03X249003I-697J-2299D01*
G01X248974Y615880D01*
X247800D01*
X247272Y615352D01*
X235509D01*
X235187Y615030D01*
X232520D01*
G37*
G36*
G01X220950Y619350D02*
X220300Y620000D01*
Y622760D01*
X220740Y623200D01*
X223402D01*
X223410Y623199D01*
G03X223546Y623194I127J1596D01*
G01X225146D01*
G03X225282Y623199I9J1601D01*
G01X225290Y623200D01*
X226170D01*
X226300Y623330D01*
X226430D01*
X226600Y623500D01*
X231560D01*
X233705Y625645D01*
X235495D01*
X236105Y626255D01*
Y628895D01*
X236320Y629110D01*
X240650D01*
X240760Y629000D01*
X241800D01*
Y623900D01*
X241215Y623315D01*
X235515D01*
X231972Y619772D01*
X224842D01*
X224421Y619350D01*
X220950D01*
G37*
G36*
G01X345140Y30961D02*
X352773Y23327D01*
X352730Y23208D01*
G03X355554Y20384I2068J-756D01*
G01X355673Y20427D01*
X358502Y17598D01*
X358745D01*
X358794Y17550D01*
X483350D01*
X492100Y26300D01*
X500100D01*
X500150Y26250D01*
X556250D01*
X570382Y40382D01*
X601158D01*
X604516Y37024D01*
Y6950D01*
X602166Y4600D01*
X318100D01*
X316775Y5925D01*
G02X316800Y6513I283J282D01*
G03X313133Y10180I-1680J1987D01*
G02X312545Y10155I-306J258D01*
G01X298604Y24096D01*
X298612Y24190D01*
G03X298300Y25674I-2592J230D01*
G01Y28166D01*
G03Y30674I-2280J1254D01*
G01Y102142D01*
X324988Y128830D01*
Y147883D01*
G03Y167471I-15933J9794D01*
G01Y177369D01*
G03Y180759I-1406J1695D01*
G01Y195512D01*
X324200Y196300D01*
X320600D01*
X320100Y196800D01*
Y203300D01*
X320500Y203700D01*
X329491D01*
X332926Y200264D01*
X332936D01*
X334269Y198931D01*
G02X334139Y198279I-283J-282D01*
G03X335512Y193300I993J-2405D01*
G02X335970Y192904I58J-396D01*
G01Y187710D01*
X338805Y184875D01*
Y163431D01*
X342267Y159969D01*
Y129867D01*
X336500Y124100D01*
Y118200D01*
X340700Y114000D01*
Y112386D01*
G03X339287Y110183I784J-2058D01*
G01X339293Y110093D01*
X320698Y91498D01*
Y49079D01*
X338816Y30961D01*
X345140D01*
G37*
G36*
G01X359000Y18800D02*
X356610Y21190D01*
X356689Y21324D01*
G03X353670Y24343I-1891J1128D01*
G01X353536Y24264D01*
X332800Y45000D01*
Y97300D01*
X335500Y100000D01*
X363700D01*
X367100Y96600D01*
Y89195D01*
X367096Y89176D01*
G03Y88290I2157J-443D01*
G01X367100Y88271D01*
Y79319D01*
X366932Y79291D01*
G03Y74945I355J-2173D01*
G01X367100Y74917D01*
Y59741D01*
G03Y55777I959J-1982D01*
G01Y45500D01*
X374800Y37800D01*
Y19700D01*
X373900Y18800D01*
X359000D01*
G37*
G36*
G01X323342Y181584D02*
X322924Y181166D01*
X322879Y181151D01*
G03X322419Y180934I703J-2087D01*
G01X316862D01*
X316282Y181514D01*
Y197186D01*
X315988Y197480D01*
X315415Y198054D01*
X308522D01*
X306576Y200000D01*
X305213D01*
X303682Y201531D01*
Y205274D01*
X303704Y205296D01*
Y206704D01*
X304300Y207300D01*
X306587D01*
X310174Y203712D01*
X310187D01*
X310250Y203650D01*
X316550D01*
X318887Y201313D01*
Y198313D01*
X318879Y198286D01*
G03Y196862I2503J-712D01*
G01X318887Y196835D01*
Y195919D01*
X319832Y194974D01*
X321284D01*
G03X321480I98J2600D01*
G01X323082D01*
X323342Y194714D01*
Y181584D01*
G37*
G36*
G01X303006Y185009D02*
X300396Y182400D01*
X295861D01*
X294724Y183537D01*
Y183885D01*
X294722Y183887D01*
Y192634D01*
X295937Y193849D01*
X308477D01*
X309732Y195104D01*
X314832D01*
X315080Y194855D01*
Y188422D01*
X314072Y187414D01*
X305411D01*
X303772Y185775D01*
X303760Y185766D01*
G03X303014Y185021I2145J-2893D01*
G01X303006Y185009D01*
G37*
G36*
G01X319102Y214554D02*
X315382Y218274D01*
Y219884D01*
X315452Y219954D01*
Y241484D01*
X316617Y242648D01*
X330347D01*
X331022Y241974D01*
Y237384D01*
X330602Y236964D01*
X328452D01*
X328432Y236984D01*
X324782D01*
X323282Y235484D01*
Y222545D01*
G02X322793Y222155I-400J0D01*
G03X324497Y219844I-492J-2146D01*
G01X324511Y220029D01*
X330037D01*
X330342Y219724D01*
Y215584D01*
X329312Y214554D01*
X319102D01*
G37*
G36*
G01X332672Y214584D02*
X331982Y215274D01*
Y220974D01*
X331692Y221264D01*
X325782D01*
X324512Y222534D01*
Y223025D01*
X324522Y223055D01*
G03Y224407I-2096J676D01*
G01X324512Y224437D01*
Y226825D01*
X324522Y226855D01*
G03Y228207I-2096J676D01*
G01X324512Y228237D01*
Y230625D01*
X324522Y230655D01*
G03Y232007I-2096J676D01*
G01X324512Y232037D01*
Y234224D01*
X324902Y234614D01*
X330482D01*
X331462Y233634D01*
Y228714D01*
X332542D01*
X332622Y228794D01*
X335862D01*
X336852Y227804D01*
Y214694D01*
X336742Y214584D01*
X332672D01*
G37*
G36*
G01X334743Y204674D02*
X331302Y208116D01*
X312185D01*
X307800Y212500D01*
Y214800D01*
X306500Y216100D01*
X304525D01*
X303425Y217200D01*
Y223914D01*
X304665Y225154D01*
X306842D01*
X308137Y226449D01*
Y231169D01*
X308772Y231804D01*
X312732D01*
X313597Y230939D01*
Y218059D01*
X318382Y213274D01*
X333132D01*
X337592Y208814D01*
Y206489D01*
X337446Y205741D01*
X336380Y204674D01*
X334743D01*
G37*
G36*
G01X312749Y632101D02*
X299868D01*
Y645060D01*
X312749D01*
Y632101D01*
G37*
G36*
G01X302039Y703651D02*
X289188D01*
Y716503D01*
X302039D01*
Y703651D01*
G37*
G36*
G01X384573Y20011D02*
X376775D01*
X376145Y20641D01*
Y34145D01*
X377000Y35000D01*
X381000D01*
X385500Y30500D01*
Y20938D01*
X384573Y20011D01*
G37*
G36*
G01X376184Y618021D02*
G03X377510Y613708I1451J-1914D01*
G02X377700Y613509I-10J-200D01*
G01Y602100D01*
X363578D01*
G03X362800Y602302I-779J-1400D01*
G01X358098D01*
X353402Y606998D01*
Y610825D01*
G03X353602Y611600I-1402J775D01*
G01Y613600D01*
G03X353422Y614336I-1602J-2D01*
G01X353400Y614379D01*
Y614958D01*
X358350Y619908D01*
X361485D01*
X365457Y623880D01*
X368348D01*
X368397Y623830D01*
X368398D01*
X368623Y623606D01*
Y623588D01*
X374925D01*
X375115Y623398D01*
X376062D01*
X377201Y622259D01*
X377104Y622122D01*
G03X376814Y621203I1311J-919D01*
G01Y619803D01*
G03X376837Y619538I1602J6D01*
G01X376854Y619436D01*
X376184Y618766D01*
Y618021D01*
G37*
G36*
G01X347698Y623902D02*
X346500Y625100D01*
Y627055D01*
G03Y629153I-1936J1049D01*
G01Y634100D01*
X346900Y634500D01*
X355800D01*
X357000Y633300D01*
Y626300D01*
X355512Y624812D01*
X355477D01*
X354567Y623902D01*
X347698D01*
G37*
G36*
G01X513700Y53500D02*
X511307Y51107D01*
X511305Y51105D01*
G03X511195Y50995I1501J-1611D01*
G01X511193Y50993D01*
X509200Y49000D01*
X507800D01*
X505322Y46522D01*
X504822D01*
X504001Y45700D01*
X492834D01*
X492577Y45957D01*
Y51374D01*
X493303Y52100D01*
X501600D01*
X503979Y54479D01*
X504049Y54487D01*
G03X506003Y56441I-235J2189D01*
G01X506011Y56511D01*
X506300Y56800D01*
X509400D01*
X510800Y55400D01*
X511289D01*
X511306Y55397D01*
G03X511590Y55372I282J1576D01*
G01X512990D01*
G03X513203Y55386I2J1601D01*
G01X513301Y55399D01*
X513700Y55000D01*
Y53500D01*
G37*
G36*
G01X531571Y31513D02*
X528708Y28650D01*
X492450D01*
X492070Y29030D01*
Y29565D01*
X492071Y29575D01*
G03X492080Y29748I-1592J170D01*
G01Y31148D01*
G03X492071Y31321I-1601J3D01*
G01X492070Y31331D01*
Y33470D01*
X492073Y33486D01*
G03X492096Y33755I-1579J270D01*
G01Y35155D01*
G03X492073Y35424I-1602J-1D01*
G01X492070Y35440D01*
Y37483D01*
X492073Y37502D01*
G03X492102Y37800I-1572J303D01*
G01Y39200D01*
G03X492073Y39498I-1601J-5D01*
G01X492070Y39517D01*
Y40900D01*
X494470Y43300D01*
X503300D01*
X505320Y45320D01*
X525760D01*
X525800Y45280D01*
X530572D01*
X531571Y44281D01*
Y31513D01*
G37*
G36*
G01X488600Y63100D02*
X487550Y62050D01*
Y57650D01*
X486900Y57000D01*
X482700D01*
X482200Y57500D01*
Y58135D01*
G03X482202Y58200I-1599J82D01*
G01Y59600D01*
G03X482200Y59665I-1601J-17D01*
G01Y62135D01*
G03X482202Y62200I-1599J82D01*
G01Y65501D01*
X482281Y65581D01*
X482304Y65594D01*
G03X483168Y66458I-1211J2075D01*
G01X483181Y66481D01*
X487175Y70475D01*
Y72362D01*
X487957Y73143D01*
G03X488577Y74372I-1557J1556D01*
G01X488587Y74437D01*
X492540Y78390D01*
X499394D01*
X501953Y80949D01*
X507581D01*
X515010Y73520D01*
X526690D01*
X527480Y72730D01*
Y63914D01*
X525856Y62290D01*
X510688D01*
X510633Y62402D01*
G03X509738Y63204I-1438J-705D01*
G01X509606Y63251D01*
Y66620D01*
X508426Y67800D01*
X503000D01*
X498300Y63100D01*
X496853D01*
G03X494147I-1353J-1985D01*
G01X488600D01*
G37*
G36*
G01X575677Y363387D02*
X573642Y365422D01*
Y381598D01*
X579309Y387265D01*
Y537747D01*
X617144Y575582D01*
Y603844D01*
X665700Y652400D01*
Y707300D01*
X667200Y708800D01*
X685400D01*
X688500Y705700D01*
Y642500D01*
X647500Y601500D01*
Y579528D01*
X638160Y570188D01*
X638108Y570175D01*
G03X636528Y568595I552J-2132D01*
G01X636515Y568543D01*
X590844Y522872D01*
Y367165D01*
X587066Y363387D01*
X575677D01*
G37*
G36*
G01X903913Y760260D02*
X922094Y723897D01*
G02X922193Y723480I-834J-418D01*
G01Y3937D01*
G02X921260Y3004I-933J0D01*
G01X742397D01*
Y11000D01*
X914197D01*
Y721812D01*
X898714Y752780D01*
X891435D01*
G03X860533I-15451J-12623D01*
G01X627655D01*
G03X596812Y752853I-15451J-12623D01*
G01X596752Y752780D01*
X594593D01*
X579110Y721812D01*
Y581723D01*
X571114D01*
Y723480D01*
G02X571213Y723897I933J-1D01*
G01X589394Y760260D01*
G02X590228Y760776I835J-417D01*
G01X903079D01*
G02X903913Y760260I-1J-933D01*
G37*
G36*
G01X665300Y291600D02*
X659450Y297450D01*
Y299650D01*
X658200Y300900D01*
X650900D01*
X650000Y300000D01*
Y298800D01*
X649854Y298654D01*
X649753Y298670D01*
G03X649498Y298690I-252J-1581D01*
G01X647898D01*
G03X647571Y298657I-4J-1601D01*
G01X647465Y298635D01*
X647200Y298900D01*
Y302537D01*
X656798Y312135D01*
X670800D01*
Y306500D01*
X670600Y306300D01*
X668100D01*
X667000Y305200D01*
Y298500D01*
X669000Y296500D01*
X683000D01*
X684158Y295342D01*
Y288564D01*
X686786Y285936D01*
Y270423D01*
X686776Y270393D01*
G03X686698Y269900I1524J-494D01*
G01Y268500D01*
G03X686776Y268007I1602J1D01*
G01X686786Y267977D01*
Y266323D01*
X686776Y266293D01*
G03X686698Y265800I1524J-494D01*
G01Y264400D01*
G03X686776Y263907I1602J1D01*
G01X686786Y263877D01*
Y263164D01*
X687900Y262050D01*
X695650D01*
X696700Y263100D01*
X704290D01*
X704765Y262626D01*
X708754D01*
Y261244D01*
X708110Y260600D01*
X704700D01*
X704668Y260568D01*
X702794D01*
X702538Y260312D01*
Y256140D01*
X703423Y255255D01*
X711065D01*
X711440Y254880D01*
Y252850D01*
X709880Y251290D01*
X709789Y251297D01*
G03X707753Y249261I-139J-1897D01*
G01X707760Y249170D01*
X707552Y248962D01*
X705690D01*
X704486Y250166D01*
X704036D01*
Y251996D01*
X703135Y252897D01*
X698604D01*
X698549Y252952D01*
X676898D01*
X675100Y254750D01*
Y274500D01*
X679600Y279000D01*
Y289200D01*
X677200Y291600D01*
X665300D01*
G37*
G36*
G01X652978Y407191D02*
X649581Y410588D01*
Y442475D01*
X652257Y445151D01*
X661215D01*
X663234Y443132D01*
Y412129D01*
X663529Y411834D01*
Y409334D01*
X661386Y407191D01*
X652978D01*
G37*
G36*
G01X631400Y447100D02*
X619000Y459500D01*
Y488500D01*
X620500Y490000D01*
X667000D01*
X690400Y513400D01*
X698900D01*
X712432Y526932D01*
X719868D01*
X737936Y545000D01*
X830500D01*
X834000Y541500D01*
Y515500D01*
X832013Y513513D01*
X799062D01*
G03X795584I-1739J-1351D01*
G01X779367D01*
G03X776043Y513757I-1767J-1313D01*
G01X775800Y513513D01*
X773585D01*
G02X773216Y514067I0J400D01*
G03X769152I-2032J849D01*
G02X768783Y513513I-369J-154D01*
G01X748027D01*
X747916Y513402D01*
X740388D01*
X735639Y508652D01*
X735184D01*
X725266Y498734D01*
X713784D01*
X709750Y494700D01*
Y479250D01*
X692338Y461838D01*
G02X691785Y461826I-283J283D01*
G03X688098Y460200I-1485J-1626D01*
G02X687898Y460000I-200J0D01*
G01X661309D01*
X648409Y447100D01*
X631400D01*
G37*
G36*
G01X679452Y413813D02*
X677861Y412222D01*
X664840D01*
X664588Y412474D01*
X664596Y412566D01*
G03X664602Y412700I-1596J139D01*
G01Y414300D01*
G03X664453Y414972I-1601J-3D01*
G01X664435Y415012D01*
Y415988D01*
X664453Y416028D01*
G03X664602Y416700I-1452J675D01*
G01Y418300D01*
G03X664453Y418972I-1601J-3D01*
G01X664435Y419012D01*
Y419988D01*
X664453Y420028D01*
G03X664602Y420700I-1452J675D01*
G01Y422300D01*
G03X664453Y422972I-1601J-3D01*
G01X664435Y423012D01*
Y424488D01*
X664453Y424528D01*
G03X664602Y425200I-1452J675D01*
G01Y426800D01*
G03X664453Y427472I-1601J-3D01*
G01X664435Y427512D01*
Y455550D01*
X665285Y456400D01*
X678150D01*
X679452Y455098D01*
Y413813D01*
G37*
G36*
G01X608500Y465500D02*
X605702Y468298D01*
Y484202D01*
X606500Y485000D01*
X616500D01*
X617500Y484000D01*
Y467000D01*
X616000Y465500D01*
X608500D01*
G37*
G36*
G01X630456Y534731D02*
X623860D01*
Y541345D01*
X630456D01*
Y534731D01*
G37*
G36*
G01X789050Y219870D02*
X790568Y218352D01*
Y217294D01*
G03X790577Y217164I901J-3D01*
G01X790579Y217150D01*
Y215964D01*
X790843Y215700D01*
X810900D01*
X811400Y215200D01*
Y211948D01*
X809086Y209634D01*
X806437D01*
X805808Y209005D01*
Y194227D01*
X804789Y193208D01*
X800284D01*
Y199227D01*
X801839Y200782D01*
Y204086D01*
X801852Y204098D01*
X800710Y205240D01*
Y210537D01*
X799830Y211417D01*
X792565D01*
X792312Y211164D01*
Y211155D01*
X791882Y210725D01*
X791880D01*
X791315Y210160D01*
Y194075D01*
X790484Y193244D01*
X785951D01*
Y204750D01*
X786330Y205129D01*
Y205989D01*
X786351Y206031D01*
G03X784292Y209500I-2151J1069D01*
G01X784214Y209503D01*
X783717Y210000D01*
X778271D01*
X777600Y209329D01*
Y194000D01*
X776400Y192800D01*
X772100D01*
X771400Y193500D01*
Y205072D01*
X769072Y207400D01*
X767600D01*
X767300Y207700D01*
Y209700D01*
X767500Y209900D01*
X769400D01*
X770079Y210579D01*
Y211046D01*
X770097Y211086D01*
G03X770180Y211464I-819J378D01*
G01Y213064D01*
G03X770097Y213442I-902J0D01*
G01X770079Y213482D01*
Y216321D01*
X769100Y217300D01*
X766300D01*
X764508Y219092D01*
Y222803D01*
X763662Y223649D01*
X760665D01*
X760185Y223169D01*
Y222676D01*
X760208Y222653D01*
Y220764D01*
X760008Y220564D01*
X758695D01*
X758037Y221222D01*
Y222650D01*
X757088Y223599D01*
X751467D01*
X750720Y222852D01*
Y217921D01*
X750387Y217588D01*
X748484D01*
X748208Y217864D01*
Y222264D01*
X748204Y222268D01*
Y222925D01*
X747802Y223327D01*
X744980D01*
X744361Y222708D01*
Y221681D01*
X744348Y221669D01*
Y220223D01*
G03X744098Y219600I651J-623D01*
G01Y218554D01*
X743108Y217564D01*
X741008D01*
X740608Y217964D01*
Y219736D01*
X740910Y220037D01*
Y220282D01*
X741220Y220592D01*
G03X741545Y221080I-1063J1060D01*
G01X741561Y221117D01*
X741708Y221264D01*
Y223692D01*
X741270Y224130D01*
X738440D01*
X738170Y223860D01*
Y221789D01*
X737906Y221526D01*
Y221281D01*
X737236Y220610D01*
X736370D01*
X735980Y221000D01*
Y223170D01*
X735040Y224110D01*
X732580D01*
X732340Y224350D01*
Y231860D01*
X732300D01*
X730893Y233267D01*
X728941D01*
X728008Y232334D01*
Y230724D01*
X727567Y230283D01*
X725144D01*
X724906Y230521D01*
Y232352D01*
X725650Y233096D01*
Y233403D01*
X725681Y233452D01*
G03X725912Y234252I-1270J800D01*
G01Y235462D01*
X725650Y235723D01*
Y239704D01*
G03Y241398I-1240J847D01*
G01Y246003D01*
G03X725912Y246850I-1240J848D01*
G01Y247822D01*
X725650Y248083D01*
Y252303D01*
G03Y253997I-1240J847D01*
G01Y258601D01*
G03Y260297I-1240J848D01*
G01Y264404D01*
X725912Y264665D01*
Y265748D01*
G03X725650Y266595I-1502J-1D01*
G01Y271200D01*
G03X725912Y272047I-1240J848D01*
G01Y273484D01*
X726073Y273515D01*
G03X726802Y274400I-173J885D01*
G01Y276000D01*
G02X727201Y276400I400J0D01*
G01X736717D01*
G03X736883I83J1900D01*
G01X757750D01*
X761250Y279900D01*
X774050D01*
X774400Y279550D01*
X778450D01*
X778950Y279050D01*
Y274500D01*
X777900Y273450D01*
X767000D01*
X766700Y273150D01*
Y265200D01*
X767125Y264775D01*
Y260825D01*
X766500Y260200D01*
Y246150D01*
X767650Y245000D01*
X768800D01*
X769700Y244100D01*
Y239250D01*
X766390Y235940D01*
Y223160D01*
X766620Y222930D01*
X772810D01*
X774008Y224128D01*
Y235508D01*
X777840Y239340D01*
Y245670D01*
X777110Y246400D01*
Y253500D01*
X776050Y254560D01*
Y255850D01*
X775300Y256600D01*
X773600D01*
X772800Y255800D01*
Y248800D01*
X772300Y248300D01*
X772163D01*
X772132Y248310D01*
G03X771174I-479J-1423D01*
G01X771143Y248300D01*
X770600D01*
X770450Y248450D01*
Y254150D01*
X770100Y254500D01*
Y259350D01*
X771340Y260590D01*
Y263240D01*
X772300Y264200D01*
X774250D01*
X775450Y263000D01*
Y261300D01*
X776160Y260590D01*
X782970D01*
X783320Y260940D01*
X785420D01*
X785445Y260915D01*
X786287D01*
X786311Y260909D01*
G03X786480Y260888I170J681D01*
G01X787280D01*
G03X787449Y260909I-1J702D01*
G01X787473Y260915D01*
X790855D01*
X791450Y260320D01*
Y258770D01*
X790860Y258180D01*
X789990D01*
X789910Y258260D01*
X786620D01*
X785555Y257195D01*
Y255590D01*
X785541Y255554D01*
G03X785602Y253627I2229J-894D01*
G01X785621Y253586D01*
Y252400D01*
X785071Y251850D01*
X783000D01*
X782632Y251482D01*
X782290D01*
G03X781388Y250580I0J-902D01*
G01Y250452D01*
X779626Y248689D01*
Y246863D01*
G03X782628I1501J0D01*
G01Y247445D01*
X783033Y247850D01*
X785371D01*
X785621Y247600D01*
Y243078D01*
X785624Y243074D01*
Y239426D01*
X787890Y237160D01*
X788280D01*
X788872Y236568D01*
Y220172D01*
X789050Y219994D01*
Y219870D01*
G37*
G36*
G01X731560Y222430D02*
X731800Y222190D01*
Y220940D01*
X731310Y220450D01*
X729770D01*
X729001Y221219D01*
X729025Y221326D01*
G03X728963Y222188I-1466J328D01*
G01X728950Y222222D01*
Y227303D01*
X728967Y227341D01*
G03Y228559I-1373J609D01*
G01X728950Y228597D01*
Y231940D01*
X729180Y232170D01*
X731281D01*
X731570Y231881D01*
Y226650D01*
X731560Y226640D01*
Y222430D01*
G37*
G36*
G01X717900Y315320D02*
X716850Y316370D01*
Y319900D01*
X717220Y320270D01*
X717398D01*
X717409Y320269D01*
G03X717590Y320258I188J1591D01*
G01X719590D01*
G03X719771Y320269I-7J1602D01*
G01X719782Y320270D01*
X721198D01*
X721209Y320269D01*
G03X721390Y320258I188J1591D01*
G01X723390D01*
G03X723571Y320269I-7J1602D01*
G01X723582Y320270D01*
X727590D01*
X728010Y319850D01*
Y315560D01*
X727770Y315320D01*
X717900D01*
G37*
G36*
G01X702700Y319850D02*
X694525D01*
X692650Y321725D01*
X688575D01*
X687950Y322350D01*
Y326500D01*
X688450Y327000D01*
X702950D01*
X703400Y326550D01*
Y320550D01*
X702700Y319850D01*
G37*
G36*
G01X676400Y307800D02*
Y316000D01*
X677300Y316900D01*
X686200D01*
X687148Y315952D01*
Y315279D01*
X692900Y309528D01*
Y308323D01*
X692378Y307802D01*
X691600D01*
G03X691539Y307800I15J-1401D01*
G01X689961D01*
G03X689900Y307802I-76J-1399D01*
G01X689100D01*
G03X689039Y307800I15J-1401D01*
G01X676400D01*
G37*
G36*
G01X695225Y308902D02*
X689996Y314131D01*
X689981Y314162D01*
G03X688932Y315195I-1981J-962D01*
G01X688350Y315777D01*
Y319700D01*
X688800Y320150D01*
X692450D01*
X694500Y318100D01*
X709009D01*
X709982Y319073D01*
X715580D01*
Y312480D01*
X715344Y312244D01*
Y311427D01*
X714374Y310457D01*
X705473D01*
X703881Y308865D01*
X695702D01*
X695685Y308868D01*
G03X695307Y308902I-386J-2168D01*
G01X695225D01*
G37*
G36*
G01X685721Y295982D02*
X683603Y298100D01*
X670000D01*
X669600Y298500D01*
Y304100D01*
X669850Y304350D01*
X670950D01*
X672200Y305600D01*
Y306138D01*
X672211Y306170D01*
G03X672302Y306700I-1511J532D01*
G01Y308100D01*
G02X672701Y308500I400J0D01*
G01X674300D01*
X674500Y308300D01*
Y307000D01*
X675400Y306100D01*
X688300D01*
X688314Y306114D01*
X692800D01*
X693250Y305664D01*
Y303203D01*
G03Y300397I1950J-1403D01*
G01Y297349D01*
X691883Y295982D01*
X685721D01*
G37*
G36*
G01X705034Y319966D02*
X704700Y320300D01*
Y325900D01*
X706200Y327400D01*
X725500D01*
X727990Y324910D01*
Y321710D01*
X727752Y321472D01*
X727529D01*
X727519Y321473D01*
G03X727350Y321482I-170J-1593D01*
G01X725350D01*
G03X725181Y321473I1J-1602D01*
G01X725171Y321472D01*
X717178D01*
X716657Y321993D01*
X710323D01*
X708296Y319966D01*
X705034D01*
G37*
G36*
G01X727050Y451950D02*
X725402Y453598D01*
Y469098D01*
X725400Y469099D01*
Y469500D01*
X724500Y470400D01*
Y474600D01*
X725100Y475200D01*
X734700D01*
X736000Y476500D01*
Y479546D01*
X736020D01*
Y482948D01*
X736000D01*
Y483636D01*
X736832Y484468D01*
X737563Y485200D01*
X748000D01*
X748800Y484400D01*
Y456300D01*
X746700Y454200D01*
X738600D01*
X736500Y452100D01*
X727200D01*
X727050Y451950D01*
G37*
G36*
G01X714300Y450600D02*
X712800Y452100D01*
Y459653D01*
X712820Y459673D01*
Y467420D01*
X714900Y469500D01*
X723300D01*
X724200Y468600D01*
Y452400D01*
X722400Y450600D01*
X714300D01*
G37*
G36*
G01X731000Y478300D02*
Y484368D01*
X730624Y484744D01*
Y488499D01*
X731325Y489200D01*
X734663D01*
X734677Y489198D01*
G03X734900Y489182I226J1586D01*
G01X736300D01*
G03X736523Y489198I-3J1602D01*
G01X736537Y489200D01*
X739163D01*
X739177Y489198D01*
G03X739400Y489182I226J1586D01*
G01X740800D01*
G03X741023Y489198I-3J1602D01*
G01X741037Y489200D01*
X743663D01*
X743677Y489198D01*
G03X743900Y489182I226J1586D01*
G01X745300D01*
G03X745523Y489198I-3J1602D01*
G01X745537Y489200D01*
X745800D01*
Y487400D01*
X745200Y486800D01*
X736000D01*
X734300Y485100D01*
Y484000D01*
X733400Y483100D01*
Y479300D01*
X732400Y478300D01*
X731000D01*
G37*
G36*
G01X711496Y571021D02*
X689569D01*
Y584177D01*
X711496D01*
Y571021D01*
G37*
G36*
G01X752700Y180700D02*
X752200Y181200D01*
Y186700D01*
X751400Y187500D01*
Y192400D01*
X747367Y196433D01*
X747410Y196552D01*
G03X747300Y198568I-2450J877D01*
G01Y203500D01*
X748800Y205000D01*
X758800D01*
X759100Y204700D01*
Y204000D01*
X756000Y200900D01*
Y188300D01*
X757100Y187200D01*
X757200D01*
X757400Y187000D01*
X758900D01*
X759200Y186700D01*
Y183700D01*
X758800Y183300D01*
X758400D01*
X755800Y180700D01*
X752700D01*
G37*
G36*
G01X764200Y172000D02*
X764100Y172100D01*
Y178900D01*
X763702Y179298D01*
Y182198D01*
X763600Y182299D01*
Y182500D01*
X762800Y183300D01*
X761700D01*
X761400Y183600D01*
Y186300D01*
X759000Y188700D01*
Y189000D01*
X758500Y189500D01*
Y202100D01*
X759600Y203200D01*
Y203791D01*
X759602Y203792D01*
Y204908D01*
X759600Y204909D01*
Y207100D01*
X760900Y208400D01*
X762500D01*
X763240Y207660D01*
Y205890D01*
X764900Y204230D01*
Y193862D01*
G03Y189938I1000J-1962D01*
G01Y188500D01*
X764871Y188429D01*
X769700Y183600D01*
Y173100D01*
X768600Y172000D01*
X764200D01*
G37*
G36*
G01X798111Y184772D02*
X794536Y181197D01*
X792774D01*
G02X792374Y181601I0J400D01*
G01Y183018D01*
G03X792335Y183373I-1601J4D01*
G01X792310Y183481D01*
X792756Y183927D01*
Y203950D01*
X792001Y204705D01*
Y209578D01*
X792725Y210302D01*
X799654D01*
X800162Y209794D01*
Y205292D01*
X798111Y203241D01*
Y184772D01*
G37*
G36*
G01X778700Y181100D02*
X778500Y181300D01*
Y181435D01*
G03X778502Y181500I-1599J82D01*
G01Y182900D01*
G03X778500Y182965I-1601J-17D01*
G01Y183700D01*
X778200Y184000D01*
Y193300D01*
X778300Y193400D01*
Y205800D01*
X778102Y205998D01*
Y209121D01*
X778180Y209200D01*
X783808D01*
X785245Y207763D01*
Y205204D01*
X783931Y203890D01*
Y193172D01*
X783600Y192841D01*
Y185400D01*
X782250Y184050D01*
X781450D01*
X780800Y183400D01*
Y181200D01*
X780700Y181100D01*
X778700D01*
G37*
G36*
G01X776998Y183502D02*
X777298Y183202D01*
Y180802D01*
X777400Y180701D01*
Y180000D01*
X777700Y179700D01*
X783100D01*
X783974Y180574D01*
Y183333D01*
X785115Y184474D01*
Y190372D01*
X785883Y191140D01*
X790387D01*
X790583Y190944D01*
Y190396D01*
X790588Y190391D01*
Y184077D01*
X791102Y183564D01*
Y179996D01*
X791155D01*
Y179959D01*
X791187D01*
X791700Y179446D01*
X797826D01*
X799375Y180995D01*
Y190850D01*
X799803Y191278D01*
X805249D01*
X805560Y190967D01*
Y181046D01*
X803242Y178728D01*
Y178586D01*
X801356Y176700D01*
X772800D01*
X771200Y178300D01*
Y183500D01*
X771150Y183550D01*
Y183950D01*
X767400Y187700D01*
Y190288D01*
G03Y193512I-1500J1612D01*
G01Y197353D01*
G02X767809Y197753I400J0D01*
G03X767829Y197752I55J899D01*
G01X769229D01*
G03X769278Y197754I-12J901D01*
G02X769700Y197354I22J-399D01*
G01Y192700D01*
X771300Y191100D01*
X775800D01*
X776100Y190800D01*
Y184700D01*
X776998Y183802D01*
Y183502D01*
G37*
G36*
G01X751915Y171053D02*
X751500Y171468D01*
Y178900D01*
X751900Y179300D01*
X753710D01*
G03X753890I90J2200D01*
G01X756400D01*
X759100Y182000D01*
X762200D01*
X762420Y181780D01*
X762409Y181684D01*
G03X762398Y181500I1591J-187D01*
G01Y180100D01*
G03X762489Y179570I1602J2D01*
G01X762500Y179538D01*
Y179200D01*
X761100Y177800D01*
Y171754D01*
X760399Y171053D01*
X751915D01*
G37*
G36*
G01X767700Y223800D02*
X767050Y224450D01*
Y235891D01*
X770202Y239042D01*
Y239152D01*
X770250Y239200D01*
Y244400D01*
X769050Y245600D01*
X767850D01*
X767050Y246400D01*
Y259700D01*
X767700Y260350D01*
Y264950D01*
X767300Y265350D01*
Y272400D01*
X767848Y272948D01*
X773152D01*
X773425Y272675D01*
Y269453D01*
X773413Y269420D01*
G03Y268400I1413J-510D01*
G01X773425Y268367D01*
Y267575D01*
X773325Y267475D01*
X770975D01*
X770150Y266650D01*
Y265100D01*
X770850Y264400D01*
Y263459D01*
X770838Y263448D01*
Y260988D01*
X769600Y259750D01*
Y259559D01*
X769598Y259558D01*
Y254292D01*
X769600Y254291D01*
Y254100D01*
X769925Y253775D01*
Y248125D01*
X770300Y247750D01*
X772650D01*
X773450Y248550D01*
Y255700D01*
X773800Y256050D01*
X775100D01*
X775548Y255602D01*
Y254352D01*
X775550Y254351D01*
Y254150D01*
X776300Y253400D01*
Y238509D01*
X773506Y235716D01*
Y235606D01*
X773275Y235375D01*
Y224575D01*
X772500Y223800D01*
X767700D01*
G37*
G36*
G01X760250Y280300D02*
X757250Y277300D01*
X754250D01*
X754023Y277527D01*
X754090Y277657D01*
G03X753900Y279319I-1334J689D01*
G01Y280850D01*
X755800Y282750D01*
X759250D01*
X760250Y281750D01*
Y280300D01*
G37*
G36*
G01X793626Y366356D02*
X792726Y367256D01*
Y374356D01*
X794426Y376056D01*
X802326D01*
X804526Y373856D01*
Y367556D01*
X803326Y366356D01*
X793626D01*
G37*
G36*
G01X793229Y350271D02*
X789186Y354314D01*
Y363216D01*
X790626Y364656D01*
X814226D01*
X814480Y364910D01*
X817079D01*
X817096Y364927D01*
X817701Y364322D01*
Y361921D01*
X817252Y361472D01*
X814719D01*
X811803Y358556D01*
X805148D01*
X804280Y357688D01*
Y354351D01*
X804243Y354314D01*
Y352021D01*
X802493Y350271D01*
X793229D01*
G37*
G36*
G01X792600Y450300D02*
X772500D01*
X771300Y451500D01*
Y459900D01*
X772800Y461400D01*
X792600D01*
X793800Y460200D01*
Y451500D01*
X792600Y450300D01*
G37*
G36*
G01X848592Y388735D02*
X818727Y418600D01*
X747950D01*
X746400Y420150D01*
Y443750D01*
X747400Y444750D01*
X831000D01*
X865500Y410250D01*
X882568D01*
X884868Y407950D01*
Y394235D01*
X884777Y394144D01*
Y391166D01*
X882346Y388735D01*
X848592D01*
G37*
G36*
G01X808900Y181031D02*
X806951D01*
X806800Y181182D01*
Y184076D01*
X807361Y184637D01*
Y204101D01*
X806546Y204916D01*
Y208975D01*
X806696Y209125D01*
X808372D01*
X808524Y208973D01*
X814208D01*
X815043Y208138D01*
Y187174D01*
X815036Y187167D01*
Y185870D01*
X813171Y184005D01*
X811874D01*
X808900Y181031D01*
G37*
G36*
G01X835400Y330600D02*
X835000Y331000D01*
Y341500D01*
X835500Y342000D01*
X844600D01*
X845400Y341200D01*
Y332200D01*
X843800Y330600D01*
X835400D01*
G37*
G36*
G01X826200Y330500D02*
X824863Y331837D01*
X824848Y331873D01*
G03X823668Y333053I-2031J-851D01*
G01X823632Y333068D01*
X822389Y334311D01*
X822374Y334347D01*
G03X821194Y335527I-2031J-851D01*
G01X821158Y335542D01*
X819559Y337141D01*
G03X819548Y337169I-2055J-791D01*
G01Y347348D01*
X826600Y354400D01*
X832900D01*
X833298Y354002D01*
Y351698D01*
X832500Y350900D01*
Y334700D01*
X833100Y334100D01*
Y331000D01*
X832600Y330500D01*
X826200D01*
G37*
G36*
G01X814471Y366111D02*
X813726Y366856D01*
X806111D01*
X805822Y367145D01*
Y379202D01*
X807306Y380686D01*
X815821D01*
X817526Y378981D01*
Y367056D01*
X816618Y366148D01*
X816528Y366154D01*
G03X816426Y366158I-114J-1598D01*
G01X815026D01*
G03X814664Y366116I2J-1602D01*
G01X814642Y366111D01*
X814471D01*
G37*
G36*
G01X835900Y343900D02*
X835400Y344400D01*
Y345000D01*
X835500Y345100D01*
Y351000D01*
X834563Y351937D01*
X834580Y352038D01*
G03X834602Y352300I-1580J265D01*
G01Y353700D01*
G03X834591Y353884I-1602J-3D01*
G01X834580Y353980D01*
X835100Y354500D01*
X843300D01*
X844900Y352900D01*
Y345100D01*
X843700Y343900D01*
X835900D01*
G37*
G36*
G01X816677Y493474D02*
X803754D01*
Y506313D01*
X816677D01*
Y493474D01*
G37*
%LPC*%
G75*
G36*
G01X119602Y546503D02*
G03X119402Y546303I0J-200D01*
G02X117203Y548502I-2202J-3D01*
G03X117403Y548702I0J200D01*
G02X119602Y546503I2202J3D01*
G37*
G36*
G01X134805Y534965D02*
G03X134276Y535294I-397J-49D01*
G02X135739Y537644I-722J2080D01*
G03X136268Y537315I397J49D01*
G02X134805Y534965I722J-2080D01*
G37*
G36*
G01X98713Y569586D02*
X99019Y569585D01*
X99819D01*
Y568785D01*
X99019D01*
X98713Y568786D01*
X97913D01*
Y569586D01*
X98713D01*
G37*
G36*
G01X128828Y568338D02*
G03X128173Y568326I-323J-236D01*
G02X128126Y570854I-1826J1230D01*
G03X128781Y570866I323J236D01*
G02X128828Y568338I1826J-1230D01*
G37*
G36*
G01X204912Y659391D02*
G03X204374Y659360I-252J-311D01*
G02X204188Y662609I-1574J1540D01*
G03X204726Y662640I252J311D01*
G02X204912Y659391I1574J-1540D01*
G37*
G36*
G01X143131Y656464D02*
G03X142501Y656433I-303J-261D01*
G02X142369Y659136I-1801J1267D01*
G03X142999Y659167I303J261D01*
G02X143131Y656464I1801J-1267D01*
G37*
G36*
G01X214850Y607850D02*
X215650D01*
Y607050D01*
X214920Y605870D01*
X214120D01*
Y606670D01*
X214850Y607850D01*
G37*
G36*
G01X505218Y17359D02*
G03X504582I-318J-242D01*
G02Y20027I-1752J1334D01*
G03X505218I318J242D01*
G02Y17359I1752J-1334D01*
G37*
G36*
G01X356839Y86337D02*
G02X355797Y88948I-3296J198D01*
G03X356469Y89253I272J293D01*
G02X356468Y89379I4200J96D01*
G01Y94479D01*
G02X364870I4201J0D01*
G01Y89379D01*
G02X357536Y86579I-4201J0D01*
G03X356839Y86337I-298J-267D01*
G37*
G36*
G01X754862Y531602D02*
G03X755477Y531571I320J239D01*
G02X755336Y528762I1622J-1489D01*
G03X754721Y528793I-320J-239D01*
G02X754862Y531602I-1622J1489D01*
G37*
G36*
G01X802526Y528267D02*
G03X803108Y528218I314J248D01*
G02X802858Y525217I1476J-1634D01*
G03X802276Y525266I-314J-248D01*
G02X802526Y528267I-1476J1634D01*
G37*
G36*
G01X753607Y244505D02*
Y243705D01*
X753600Y243700D01*
Y242900D01*
X752800D01*
Y243700D01*
X752807Y243705D01*
Y244505D01*
X753607D01*
G37*
G36*
G01X735560Y230040D02*
Y229240D01*
X735570Y229000D01*
Y228200D01*
X734770D01*
Y229000D01*
X734760Y229240D01*
Y230040D01*
X735560D01*
G37*
G36*
G01X786350Y227100D02*
Y226300D01*
X786500Y226000D01*
Y225200D01*
X785700D01*
Y226000D01*
X785550Y226300D01*
Y227100D01*
X786350D01*
G37*
G36*
G01X805410Y213740D02*
Y212940D01*
X804610D01*
X804250Y212930D01*
X803450D01*
Y213730D01*
X804250D01*
X804610Y213740D01*
X805410D01*
G37*
G36*
G01X800800Y213750D02*
X801050Y213730D01*
X801850D01*
Y212930D01*
X801050D01*
X800800Y212950D01*
X800000D01*
Y213750D01*
X800800D01*
G37*
G36*
G01X798400D02*
Y212950D01*
X797600D01*
X797319Y212924D01*
X796519D01*
Y213724D01*
X797319D01*
X797600Y213750D01*
X798400D01*
G37*
G36*
G01X794919Y213724D02*
Y212924D01*
X794119D01*
X793869Y212894D01*
X793069D01*
Y213694D01*
X793869D01*
X794119Y213724D01*
X794919D01*
G37*
G36*
G01X804656Y208063D02*
Y207263D01*
X804716Y207145D01*
Y206345D01*
X803916D01*
Y207145D01*
X803856Y207263D01*
Y208063D01*
X804656D01*
G37*
G36*
G01X736448Y264402D02*
X736617D01*
X736792Y264576D01*
X740917D01*
X741248Y264908D01*
Y266258D01*
X742242Y267252D01*
X743096D01*
X743108Y267253D01*
G02X743456I174J-1492D01*
G01X743468Y267252D01*
X744008D01*
X744752Y266508D01*
Y266072D01*
X744755Y266053D01*
G02Y265469I-1473J-292D01*
G01X744752Y265450D01*
Y260808D01*
X745426Y260133D01*
Y239783D01*
X745808Y239402D01*
X747442D01*
X747848Y239808D01*
Y265892D01*
X746474Y267267D01*
Y270633D01*
X747698Y271858D01*
Y273008D01*
X748492Y273802D01*
X750158D01*
X751152Y272808D01*
Y267408D01*
X751602Y266958D01*
Y239658D01*
X751758Y239502D01*
X754142D01*
X754248Y239608D01*
Y260508D01*
X754798Y261058D01*
Y263942D01*
X753848Y264892D01*
Y272608D01*
X755042Y273802D01*
X756608D01*
X757752Y272658D01*
Y265208D01*
X758802Y264158D01*
Y260692D01*
X757652Y259542D01*
Y239858D01*
X758008Y239502D01*
X759992D01*
X760548Y240058D01*
Y266492D01*
X759570Y267471D01*
G02X759371Y267670I530J729D01*
G01X759148Y267892D01*
Y270233D01*
X759942Y271026D01*
X762433D01*
X763002Y270458D01*
Y267708D01*
X764002Y266708D01*
Y242158D01*
X764308Y241852D01*
X764600D01*
X764644Y241875D01*
G02X766066I711J-1323D01*
G01X766110Y241852D01*
X766308D01*
X767002Y241158D01*
Y239142D01*
X766358Y238498D01*
X764208D01*
X764002Y238292D01*
Y233742D01*
X763902Y233642D01*
Y233318D01*
X763578D01*
X763458Y233198D01*
X757692D01*
X757572Y233318D01*
X757398D01*
Y233492D01*
X757098Y233792D01*
Y234692D01*
X756342Y235448D01*
X745708D01*
X745152Y234892D01*
Y233292D01*
X744902Y233042D01*
Y232848D01*
X744708D01*
X744583Y232724D01*
X738593D01*
X738467Y232848D01*
X738398D01*
Y232917D01*
X738060Y233254D01*
Y238258D01*
X739304Y239502D01*
X740842D01*
X741274Y239933D01*
Y256917D01*
X740523Y257668D01*
X736761D01*
X736530Y257898D01*
X736448D01*
Y257980D01*
X736086Y258342D01*
Y263869D01*
X736448Y264232D01*
Y264402D01*
G37*
G36*
G01X783218Y217274D02*
Y218589D01*
X782750Y219056D01*
Y221654D01*
G02X785754I1502J0D01*
G01Y220300D01*
X786470Y219583D01*
Y219375D01*
X786498Y219328D01*
G02X786620Y218874I-779J-453D01*
G01Y217274D01*
G02X785719Y216372I-901J-1D01*
G01X784119D01*
G02X783218Y217274I1J902D01*
G37*
G36*
G01X779102Y213900D02*
G02X778200Y212998I-902J0D01*
G01X776600D01*
G02X775698Y213900I0J902D01*
G01Y215500D01*
G02X775948Y216123I901J0D01*
G01Y216677D01*
G02X775698Y217300I651J623D01*
G01Y218900D01*
G02X775948Y219523I901J0D01*
G01Y221773D01*
X776891Y222716D01*
G02X779015Y220592I1062J-1062D01*
G01X778952Y220529D01*
Y219401D01*
X778979Y219354D01*
G02X779102Y218900I-779J-455D01*
G01Y217300D01*
G02X778979Y216846I-902J1D01*
G01X778952Y216799D01*
Y216001D01*
X778979Y215954D01*
G02X779102Y215500I-779J-455D01*
G01Y213900D01*
G37*
G36*
G01X725350Y318280D02*
Y317480D01*
X724550D01*
X724190Y317460D01*
X723390D01*
Y318260D01*
X724190D01*
X724550Y318280D01*
X725350D01*
G37*
G36*
G01Y324280D02*
Y323480D01*
X724550D01*
X724190Y323460D01*
X723390D01*
Y324260D01*
X724190D01*
X724550Y324280D01*
X725350D01*
G37*
G36*
G01X858728Y411965D02*
G03X859343Y411950I314J248D01*
G02X859272Y409135I1657J-1450D01*
G03X858657Y409150I-314J-248D01*
G02X858728Y411965I-1657J1450D01*
G37*
G36*
G01X867560Y397018D02*
G03X866894I-333J-222D01*
G02Y399898I-2167J1440D01*
G03X867560I333J222D01*
G02X871894I2167J-1440D01*
G03X872560I333J222D01*
G02Y397018I2167J-1440D01*
G03X871894I-333J-222D01*
G02X867560I-2167J1440D01*
G37*
G36*
G01X808516Y207145D02*
Y206345D01*
X807716D01*
Y207145D01*
X807656Y207263D01*
Y208063D01*
X808456D01*
Y207263D01*
X808516Y207145D01*
G37*
G54D105*
X755900Y274950D03*
Y278750D03*
G54D101*
X775900Y207600D03*
X759400Y243700D03*
X765600D03*
X753300Y250000D03*
X759450D03*
X765550D03*
X771950Y250040D03*
X771700Y256250D03*
X747000Y256300D03*
X753150D03*
X759400D03*
X765600D03*
X779700Y207600D03*
X768150Y250040D03*
X767900Y256250D03*
G54D93*
X96570Y581730D03*
X733859Y272048D03*
X777953Y256300D03*
X737009Y240552D03*
X743283Y272060D03*
X771655Y237402D03*
G54D106*
X720490Y317860D03*
Y323860D03*
G54D102*
X782200Y216400D03*
G54D98*
X339331Y49803D03*
G54D97*
X360669D03*
X339331Y91929D03*
G54D100*
X789802Y207292D03*
X793602D03*
G54D94*
X135350Y596800D03*
X690750Y308900D03*
Y305100D03*
G54D104*
X785950Y233060D03*
G54D92*
X126337Y554085D03*
X59200Y582200D03*
X138900Y525999D03*
X133800Y528500D03*
X108371Y577258D03*
X117400Y567650D03*
X134650Y612900D03*
X136100Y656300D03*
X125100Y656700D03*
X130800Y656100D03*
X189000Y659900D03*
X193500Y663000D03*
X296800Y665081D03*
X288700Y667900D03*
X300100Y670300D03*
X311715Y20397D03*
X310353Y62159D03*
X326553Y34687D03*
X496430Y22890D03*
X491270Y18877D03*
X524950Y16120D03*
X596489Y14110D03*
X601311Y13521D03*
X496700Y32100D03*
X582219Y386612D03*
X610200Y555400D03*
X628160Y569095D03*
X619400Y570451D03*
X614000Y561250D03*
X606600Y551100D03*
X666216Y470684D03*
X682400Y463400D03*
X677275Y485625D03*
X683583Y485841D03*
X702824Y476476D03*
X696800Y476400D03*
X689100Y507900D03*
X696000Y508400D03*
X763809Y537191D03*
X782709Y537691D03*
X795922Y531500D03*
X821050Y533350D03*
X813150Y533450D03*
X857581Y391433D03*
X851100Y407500D03*
X872750Y403400D03*
G54D103*
X785950Y229625D03*
G54D95*
X187795Y592914D03*
G54D96*
X564803Y24409D03*
X574803D03*
X584803D03*
G54D99*
X346457Y66850D03*
Y57007D03*
X353543Y70787D03*
Y62913D03*
Y55039D03*
X346457Y74724D03*
Y84567D03*
X353543Y78661D03*
G54D91*
X102700Y507100D03*
X586155Y393023D03*
G54D90*
X155195Y553466D03*
X68778Y505277D03*
X70978D03*
X79968Y505366D03*
X82168D03*
X63151Y505377D03*
X65351D03*
X74273Y505379D03*
X76473D03*
X85573Y505500D03*
X87773D03*
X91173D03*
X93373D03*
X96800D03*
X99000D03*
X37332Y520171D03*
Y522371D03*
X37375Y525895D03*
Y528095D03*
X37365Y531538D03*
Y533738D03*
X107174Y534124D03*
X37258Y537154D03*
X107174Y537524D03*
X37258Y539354D03*
X37358Y542781D03*
Y544981D03*
X37403Y548408D03*
Y550608D03*
X147140Y553435D03*
X150540D03*
X151795Y553466D03*
X37385Y554053D03*
Y556253D03*
X142337Y556786D03*
X145737D03*
X147140Y556835D03*
X150540D03*
X151795Y556866D03*
X155195D03*
X144867Y558691D03*
X148267D03*
X149557Y558723D03*
X152957D03*
X140187Y558791D03*
X143587D03*
X102576Y559066D03*
X155401Y559767D03*
X37300Y559800D03*
X102576Y561266D03*
X37300Y562000D03*
X101819Y563185D03*
X95913Y563186D03*
X94070Y563215D03*
X40168Y565616D03*
Y569016D03*
X49656Y572895D03*
X47550Y578550D03*
Y581950D03*
X62650Y575200D03*
X59600Y576950D03*
X62650Y578600D03*
X66050D03*
X142337Y547786D03*
X145737D03*
X147140Y547835D03*
X150540D03*
X151795Y547866D03*
X152957Y567723D03*
X144867Y567691D03*
X148267D03*
X149557Y567723D03*
X140187Y567791D03*
X143587D03*
X147516Y569104D03*
X101819Y569185D03*
X95913Y569186D03*
X91670Y569215D03*
X94070D03*
X147516Y571504D03*
X95087Y571699D03*
X97487D03*
X104930Y575252D03*
Y577652D03*
X130800Y595400D03*
X132400Y596800D03*
X138300D03*
X139489Y598037D03*
X130800Y598800D03*
X126700Y619200D03*
X128900D03*
X125992Y601754D03*
Y603954D03*
X198355Y517651D03*
X201755D03*
X203000Y517700D03*
X206400D03*
X207745Y517749D03*
X211145D03*
X197100Y517800D03*
X212400D03*
X215800D03*
X158458Y516577D03*
Y518777D03*
X158488Y521034D03*
Y523234D03*
X158200Y525200D03*
X162500Y526600D03*
X198355Y523251D03*
X201755D03*
X203000Y523300D03*
X206400D03*
X207745Y523349D03*
X211145D03*
X197100Y523400D03*
X212400D03*
X215800D03*
X193700Y526800D03*
X171302Y575158D03*
X186900Y557500D03*
X183500D03*
X188750Y557550D03*
X183500Y560900D03*
X186900D03*
X188750Y560950D03*
X195790Y568400D03*
X197990D03*
X182848Y569951D03*
X183205Y574091D03*
X192759Y575797D03*
X196159D03*
X192759Y579197D03*
X196159D03*
X193789Y580925D03*
X195330Y581740D03*
X199810Y558690D03*
X202010D03*
X200930Y581740D03*
X179805Y579691D03*
X183205D03*
X184789Y580925D03*
X179805Y583091D03*
X183205D03*
X180460Y606280D03*
Y608680D03*
Y609980D03*
Y612380D03*
X174460Y608680D03*
Y609980D03*
Y612380D03*
X172760Y613680D03*
X188920Y612440D03*
X192380Y617240D03*
X215250Y610850D03*
X251470Y625237D03*
X253870D03*
X223146Y626795D03*
X225546D03*
X251470Y619237D03*
X253870D03*
X223146Y620795D03*
X225546D03*
X372700Y29900D03*
Y32100D03*
X378300D03*
Y29900D03*
X366220Y604364D03*
X369020D03*
X360400Y604700D03*
X363200D03*
X373900Y605900D03*
X356000Y611200D03*
Y614000D03*
X374616Y619403D03*
X365713Y621507D03*
X368513D03*
X374616Y621603D03*
X347500Y630400D03*
X350900D03*
X352300D03*
X355700D03*
X494300Y48915D03*
X497700D03*
X499311Y50765D03*
X501511D03*
X506195Y53097D03*
X509595D03*
X511190Y53173D03*
X494294Y35555D03*
X494300Y37400D03*
Y39600D03*
X484400Y60000D03*
Y61800D03*
X511800Y63900D03*
X484400Y64000D03*
X489553Y65237D03*
X491753D03*
X511800Y66100D03*
X709273Y252783D03*
X684500Y264000D03*
Y266200D03*
Y268100D03*
Y270300D03*
X655565Y302966D03*
X657765D03*
X651365Y303066D03*
X653565D03*
X668900Y308500D03*
X661000Y412300D03*
Y414700D03*
Y416300D03*
Y418700D03*
Y420300D03*
Y422700D03*
Y424800D03*
Y427200D03*
X667000Y414700D03*
Y416300D03*
Y418700D03*
Y420300D03*
Y422700D03*
Y424800D03*
Y427200D03*
X773300Y200800D03*
X776700D03*
X787537Y200818D03*
X773300Y204200D03*
X776700D03*
X787537Y204218D03*
X789802Y205342D03*
X804316Y205345D03*
X775900Y205800D03*
X804256Y209063D03*
X789802Y209242D03*
X775900Y209400D03*
X791069Y213294D03*
X807410Y213340D03*
X782200Y213500D03*
X789719Y216874D03*
X743100Y220000D03*
X735170Y226200D03*
X735160Y232040D03*
X776300Y232700D03*
Y235100D03*
X785950Y235970D03*
X727629Y236514D03*
Y238914D03*
X753200Y241900D03*
X759400D03*
X728170Y242500D03*
Y244900D03*
X759400Y245500D03*
X765600D03*
X753207Y245505D03*
X753300Y248200D03*
X759450D03*
X765550D03*
X727940Y248650D03*
X779750Y250450D03*
X727940Y251050D03*
X753300Y251800D03*
X759450D03*
X765550D03*
X771950Y251840D03*
X779750Y253250D03*
X771700Y254450D03*
X747000Y254500D03*
X753150D03*
X759400D03*
X765600D03*
X727650Y255350D03*
Y257750D03*
X771700Y258050D03*
X747000Y258100D03*
X753150D03*
X759400D03*
X765600D03*
X773650Y258250D03*
X775050D03*
X780880Y258940D03*
X782280D03*
X786180Y259090D03*
X787580D03*
X774400Y261050D03*
X727500Y261100D03*
Y263500D03*
X727863Y267502D03*
X765700Y267800D03*
X727863Y269902D03*
X765700Y270200D03*
X729900Y274000D03*
X754100Y274950D03*
X757700D03*
X774500Y277800D03*
X775900D03*
X688920Y325440D03*
X692320D03*
X688800Y308900D03*
X684000Y311300D03*
X687400D03*
X704880Y314340D03*
X708280D03*
X692320Y316440D03*
X684000Y302300D03*
X687400D03*
X688800Y305100D03*
X708280Y323340D03*
X717190Y323860D03*
X734500Y486984D03*
X755800Y183500D03*
Y186900D03*
X765800Y179700D03*
Y181900D03*
X764800Y183500D03*
Y186900D03*
X761300Y203600D03*
Y205000D03*
X794573Y183418D03*
X796537Y200818D03*
Y204218D03*
X793602Y205342D03*
Y209242D03*
X782300Y200800D03*
Y204200D03*
X779700Y205800D03*
X775100Y181100D03*
X803392Y181109D03*
X788973Y181218D03*
X775100Y183300D03*
X803392Y183309D03*
X788973Y183418D03*
X760200Y179700D03*
X770300Y232700D03*
Y235100D03*
X773590Y246480D03*
X768150Y248240D03*
Y251840D03*
X767900Y254450D03*
Y258050D03*
X796426Y370056D03*
X793026Y361056D03*
X796426D03*
X814626Y362756D03*
X816826D03*
X808116Y205345D03*
X810862Y204183D03*
Y200783D03*
X808992Y183309D03*
X838500Y334200D03*
X829500D03*
X831200Y351900D03*
X814626Y368356D03*
X836800Y351900D03*
%LPD*%
G75*
G36*
G01X738800Y233225D02*
X738562Y233462D01*
Y238050D01*
X739512Y239000D01*
X741050D01*
X741775Y239725D01*
Y257125D01*
X740731Y258169D01*
X736969D01*
X736588Y258550D01*
Y263662D01*
X737000Y264075D01*
X741125D01*
X741750Y264700D01*
Y266050D01*
X742450Y266750D01*
X743800D01*
X744250Y266300D01*
Y260600D01*
X744925Y259925D01*
Y253283D01*
X744924Y253275D01*
G03Y253023I1497J-126D01*
G01X744925Y253015D01*
Y239575D01*
X745600Y238900D01*
X747650D01*
X748350Y239600D01*
Y249053D01*
G03X748352Y249100I-899J62D01*
G01Y250700D01*
G03X748350Y250747I-901J-15D01*
G01Y266100D01*
X746975Y267475D01*
Y270425D01*
X748200Y271650D01*
Y272800D01*
X748700Y273300D01*
X749950D01*
X750650Y272600D01*
Y267200D01*
X751100Y266750D01*
Y239450D01*
X751550Y239000D01*
X754350D01*
X754750Y239400D01*
Y260300D01*
X755300Y260850D01*
Y264150D01*
X754350Y265100D01*
Y272400D01*
X755250Y273300D01*
X756400D01*
X757250Y272450D01*
Y265000D01*
X758300Y263950D01*
Y260900D01*
X757150Y259750D01*
Y239650D01*
X757800Y239000D01*
X760200D01*
X761050Y239850D01*
Y266700D01*
X759650Y268100D01*
Y270025D01*
X760150Y270525D01*
X762225D01*
X762500Y270250D01*
Y267500D01*
X763500Y266500D01*
Y241950D01*
X764100Y241350D01*
X766100D01*
X766500Y240950D01*
Y239350D01*
X766150Y239000D01*
X764000D01*
X763500Y238500D01*
Y233950D01*
X763250Y233700D01*
X757900D01*
X757600Y234000D01*
Y234900D01*
X756550Y235950D01*
X745500D01*
X744650Y235100D01*
Y233500D01*
X744375Y233225D01*
X738800D01*
G37*
%LPC*%
G75*
G36*
G01X749807Y244505D02*
Y243705D01*
X749800Y243700D01*
Y242900D01*
X749000D01*
Y243700D01*
X749007Y243705D01*
Y244505D01*
X749807D01*
G37*
G54D101*
X755600Y243700D03*
X749500Y250000D03*
X755650D03*
X743200Y256300D03*
X749350D03*
X755600D03*
G54D107*
X743250Y243725D03*
G54D90*
Y241900D03*
X749400D03*
X755600D03*
Y245500D03*
X749407Y245505D03*
X743250Y245550D03*
X749500Y248200D03*
X755650D03*
X749500Y251800D03*
X755650D03*
X743200Y254500D03*
X749350D03*
X755600D03*
X743200Y258100D03*
X749350D03*
X755600D03*
X749450Y267700D03*
Y270100D03*
%LPD*%
G75*
G54D10*
X8500Y18279D03*
Y28279D03*
Y38279D03*
Y48279D03*
Y58279D03*
Y68279D03*
X13721Y8500D03*
X8500Y13279D03*
Y23279D03*
Y33279D03*
Y43279D03*
Y53279D03*
Y63279D03*
Y78279D03*
Y88279D03*
Y98279D03*
Y108279D03*
Y118279D03*
Y128279D03*
Y73279D03*
Y83279D03*
Y93279D03*
Y103279D03*
Y113279D03*
Y123279D03*
Y133279D03*
Y138279D03*
Y148279D03*
Y158279D03*
Y168279D03*
Y178279D03*
Y188279D03*
Y198279D03*
Y143279D03*
Y153279D03*
Y163279D03*
Y173279D03*
Y183279D03*
Y193279D03*
Y208279D03*
Y218279D03*
Y228279D03*
Y238279D03*
Y248279D03*
Y258279D03*
Y203279D03*
Y213279D03*
Y223279D03*
Y233279D03*
Y243279D03*
Y253279D03*
Y263279D03*
Y268279D03*
Y278279D03*
Y288279D03*
Y298279D03*
Y308279D03*
Y318279D03*
Y328279D03*
Y273279D03*
Y283279D03*
Y293279D03*
Y303279D03*
Y313279D03*
Y323279D03*
Y338279D03*
Y348279D03*
Y358279D03*
Y368279D03*
Y378279D03*
Y388279D03*
Y333279D03*
Y343279D03*
Y353279D03*
Y363279D03*
Y373279D03*
Y383279D03*
Y393279D03*
Y398279D03*
Y408279D03*
Y418279D03*
Y428279D03*
Y438279D03*
Y448279D03*
Y458279D03*
Y403279D03*
Y413279D03*
Y423279D03*
Y433279D03*
Y443279D03*
Y453279D03*
Y468279D03*
Y478279D03*
Y488279D03*
Y498279D03*
Y508279D03*
Y518279D03*
Y528279D03*
Y463279D03*
Y473279D03*
Y483279D03*
Y493279D03*
Y503279D03*
Y513279D03*
Y523279D03*
Y538279D03*
Y548279D03*
Y558279D03*
Y568279D03*
Y578279D03*
Y588279D03*
Y533279D03*
Y543279D03*
Y553279D03*
Y563279D03*
Y573279D03*
Y583279D03*
Y593279D03*
Y598279D03*
Y608279D03*
Y618279D03*
Y628279D03*
Y638279D03*
Y648279D03*
Y658279D03*
Y603279D03*
Y613279D03*
Y623279D03*
Y633279D03*
Y643279D03*
Y653279D03*
Y668279D03*
Y678279D03*
Y688279D03*
Y698279D03*
Y708279D03*
Y718279D03*
Y663279D03*
Y673279D03*
Y683279D03*
Y693279D03*
Y703279D03*
Y713279D03*
X8892Y723187D03*
X11090Y727806D03*
X13500Y732400D03*
X78721Y8500D03*
X68721D03*
X58721D03*
X48721D03*
X38721D03*
X28721D03*
X18721D03*
X73721D03*
X53721D03*
X43721D03*
X33721D03*
X23721D03*
X63721D03*
X75534Y625175D03*
X75300Y679300D03*
Y674300D03*
X78370Y724300D03*
Y719500D03*
X28100Y755600D03*
X33100D03*
X69057Y755280D03*
X74057D03*
X20300Y746200D03*
X15800Y736900D03*
X18100Y741500D03*
X22600Y750800D03*
X79057Y755280D03*
X108721Y8500D03*
X98721D03*
X88721D03*
X112197Y65406D03*
Y60406D03*
Y55406D03*
X103721Y8500D03*
X93721D03*
X83721D03*
X112197Y75406D03*
Y85406D03*
Y95406D03*
Y105406D03*
Y115406D03*
Y120406D03*
Y110406D03*
Y100406D03*
Y90406D03*
Y80406D03*
Y70406D03*
Y145406D03*
Y195406D03*
Y185406D03*
Y175406D03*
Y165406D03*
Y155406D03*
Y200406D03*
Y190406D03*
Y180406D03*
Y170406D03*
Y160406D03*
Y150406D03*
Y265406D03*
Y255406D03*
Y245406D03*
Y235406D03*
Y225406D03*
Y215406D03*
Y205406D03*
Y260406D03*
Y250406D03*
Y240406D03*
Y230406D03*
Y220406D03*
Y210406D03*
Y325406D03*
Y315406D03*
Y305406D03*
Y295406D03*
Y285406D03*
Y275406D03*
Y330406D03*
Y320406D03*
Y310406D03*
Y300406D03*
Y290406D03*
Y280406D03*
Y270406D03*
Y390406D03*
Y380406D03*
Y370406D03*
Y360406D03*
Y350406D03*
Y395406D03*
Y385406D03*
Y375406D03*
Y365406D03*
Y355406D03*
Y345406D03*
Y335406D03*
Y340406D03*
Y420406D03*
Y410406D03*
Y400406D03*
Y425406D03*
Y415406D03*
Y405406D03*
X103600Y637800D03*
X103500Y645500D03*
Y650535D03*
X80334Y625175D03*
X99600Y673500D03*
Y678500D03*
X86500Y703100D03*
X86600Y708300D03*
X96800Y662000D03*
X90200Y667100D03*
X85400D03*
X99600Y683500D03*
X81300Y675100D03*
Y680100D03*
X134223Y691027D03*
X83170Y724300D03*
Y719500D03*
X122435Y666782D03*
Y661982D03*
X144057Y755280D03*
X134057D03*
X124057D03*
X114057D03*
X104057D03*
X94057D03*
X84057D03*
X89057D03*
X99057D03*
X109057D03*
X119057D03*
X129057D03*
X139057D03*
X91700Y744800D03*
X96500D03*
X101300D03*
X106100D03*
X110900D03*
X115700D03*
X120500D03*
X125300D03*
X159400Y498300D03*
X165030Y539170D03*
X156391Y590972D03*
X197400Y549000D03*
X153624Y543694D03*
X161750Y535000D03*
X170545Y539779D03*
X175200Y555000D03*
X202380Y567970D03*
X207820Y570860D03*
X206900Y577100D03*
X190500Y547100D03*
X178100Y548700D03*
X155660Y599140D03*
X170200Y603600D03*
X155343Y609168D03*
X158862Y614107D03*
X177750Y603250D03*
X208300Y704985D03*
X203500D03*
X198700D03*
X193900D03*
X155400Y717700D03*
X204057Y755280D03*
X194057D03*
X184057D03*
X174057D03*
X164057D03*
X154057D03*
X149057D03*
X159057D03*
X169057D03*
X179057D03*
X189057D03*
X199057D03*
X209057D03*
X239200Y527000D03*
X220832Y551776D03*
X231892Y546871D03*
X221956Y544587D03*
X223192Y567000D03*
X219688Y587796D03*
X219648Y576801D03*
X219485Y582348D03*
X218801Y571096D03*
X232167Y554962D03*
X219627Y562552D03*
X219691Y557104D03*
X225932Y548276D03*
X222700Y704985D03*
X217900D03*
X213100D03*
X249500Y719500D03*
Y724300D03*
X274057Y755280D03*
X264057D03*
X254057D03*
X244057D03*
X234057D03*
X224057D03*
X214057D03*
X219057D03*
X229057D03*
X239057D03*
X249057D03*
X259057D03*
X269057D03*
X249500Y729100D03*
Y733900D03*
Y738700D03*
X315120Y8500D03*
X310120D03*
X305120D03*
X300120D03*
X296020Y9420D03*
Y14420D03*
Y19420D03*
Y24420D03*
Y29420D03*
X321382Y197574D03*
X296282Y189224D03*
Y184424D03*
X301082D03*
Y189224D03*
X335132Y195874D03*
X305862Y210014D03*
X334882Y215874D03*
Y220874D03*
X321382Y202374D03*
X335132Y205974D03*
X335200Y640100D03*
X330400D03*
X335000Y615400D03*
X335300Y609800D03*
X335000Y621200D03*
X325600Y640100D03*
X322586Y653754D03*
X317786D03*
X312986D03*
X308186D03*
X330200Y709300D03*
X334650Y689700D03*
X335350Y684650D03*
X315520Y711720D03*
X325700Y711600D03*
X320320Y711720D03*
X305500Y721000D03*
X310500D03*
X304150Y674700D03*
X299350D03*
X334057Y755280D03*
X324057D03*
X314057D03*
X304057D03*
X294057D03*
X284057D03*
X279057D03*
X289057D03*
X299057D03*
X309057D03*
X319057D03*
X329057D03*
X339057D03*
X305500Y726000D03*
X310500D03*
X359929Y626617D03*
X384365Y605713D03*
X381638Y755280D03*
X384809Y752321D03*
X387045Y747849D03*
X389281Y743376D03*
X391517Y738904D03*
X393753Y734432D03*
X395989Y729960D03*
X398225Y725488D03*
X344057Y755280D03*
X521634Y38901D03*
Y34101D03*
X516834Y38901D03*
Y34101D03*
X526434Y43701D03*
X521634D03*
X516834D03*
X520000Y63400D03*
X515200Y66440D03*
X520585Y68348D03*
X536794Y77373D03*
X531664Y78463D03*
X515915Y80576D03*
X520310Y76700D03*
X508668Y79607D03*
X503550Y79500D03*
X511100Y75060D03*
X506100D03*
X511100Y70060D03*
X525200Y71440D03*
X516628Y71806D03*
X600700Y35700D03*
X595500Y35600D03*
X595700Y29800D03*
X600900Y29700D03*
X576610Y388416D03*
Y393416D03*
X576512Y369625D03*
Y364825D03*
X581312Y369625D03*
Y364825D03*
X576610Y398416D03*
Y403416D03*
Y408416D03*
Y413416D03*
Y418416D03*
Y423416D03*
Y428416D03*
Y433416D03*
Y438416D03*
Y443416D03*
Y448416D03*
Y453416D03*
Y458416D03*
Y463416D03*
Y468416D03*
Y473416D03*
Y478416D03*
Y483416D03*
Y488416D03*
Y493416D03*
Y498416D03*
Y503416D03*
Y508416D03*
Y513416D03*
Y518416D03*
Y523416D03*
Y528416D03*
Y533416D03*
Y538416D03*
Y543416D03*
Y548416D03*
Y553416D03*
Y558416D03*
Y563416D03*
Y568416D03*
Y573416D03*
Y578416D03*
Y583416D03*
Y588416D03*
Y593416D03*
Y598416D03*
Y603416D03*
Y608416D03*
Y613416D03*
Y618416D03*
Y623416D03*
Y628416D03*
Y633416D03*
Y638416D03*
Y643416D03*
Y648416D03*
Y653416D03*
Y658416D03*
Y663416D03*
Y668416D03*
Y673416D03*
Y678416D03*
Y683416D03*
Y688416D03*
Y693416D03*
Y698416D03*
Y703416D03*
Y708416D03*
Y713416D03*
Y718416D03*
X577063Y723309D03*
X579299Y727781D03*
X581535Y732253D03*
X583771Y736725D03*
X586007Y741198D03*
X588243Y745670D03*
X590479Y750142D03*
X592715Y754614D03*
X609200Y330400D03*
X658000Y431500D03*
Y409000D03*
Y414000D03*
Y426000D03*
Y420500D03*
X642700Y454400D03*
X642500Y449100D03*
X642600Y459500D03*
X610000Y467500D03*
X609000Y473500D03*
Y478500D03*
Y483500D03*
X645200Y521900D03*
X650400Y517600D03*
X656400Y517500D03*
X661500Y517600D03*
X621600Y486619D03*
X626958Y486419D03*
X642500Y464700D03*
X629500Y482500D03*
Y477000D03*
Y471500D03*
X635000Y482500D03*
Y476500D03*
Y471000D03*
X615500Y529800D03*
X616710Y534500D03*
X657000Y555000D03*
X662000D03*
X661887Y560010D03*
X656887D03*
X645300Y655200D03*
Y650400D03*
Y645600D03*
Y640800D03*
X655000Y705000D03*
Y700200D03*
Y695400D03*
Y690600D03*
X645300Y684000D03*
Y679200D03*
Y674400D03*
Y669600D03*
Y664800D03*
Y660000D03*
X655000Y685800D03*
X659722Y755280D03*
X649722D03*
X639722D03*
X634722D03*
X644722D03*
X654722D03*
X664722D03*
X729930Y211940D03*
X723210Y209850D03*
X709650Y249400D03*
X714100Y238800D03*
X711000Y232800D03*
X722961Y300982D03*
X720530Y312210D03*
X733696Y300991D03*
X726800Y313113D03*
X727996Y303699D03*
X711322Y294199D03*
X706997Y283155D03*
X711029Y279114D03*
X713789Y284135D03*
X697960Y292400D03*
X703526Y275939D03*
X714519Y275114D03*
X707604Y272070D03*
X698773Y278597D03*
X709600Y299400D03*
X718600Y304300D03*
X715200Y300000D03*
X709500Y308400D03*
X693200Y279550D03*
X702109Y297903D03*
X702400Y286700D03*
X700700Y305100D03*
X716060Y309320D03*
X706600Y303800D03*
X691774Y288967D03*
X714400Y268600D03*
X718260Y294951D03*
X708483Y311988D03*
X713283D03*
X723900Y326350D03*
X718940Y326270D03*
X714900Y453600D03*
X715200Y459600D03*
X706700Y413900D03*
X710200Y417400D03*
Y422900D03*
Y427900D03*
X698700Y417600D03*
Y423100D03*
Y428100D03*
X676000Y431000D03*
X671000D03*
Y421000D03*
X676000D03*
X671000Y426000D03*
X676000D03*
X715200Y465000D03*
X689500Y518500D03*
Y524000D03*
X694738Y523940D03*
X694690Y519034D03*
X670400Y565500D03*
Y560700D03*
Y555900D03*
Y551100D03*
Y546300D03*
Y541500D03*
Y536700D03*
X687015Y658100D03*
Y653300D03*
Y648500D03*
Y643700D03*
Y682100D03*
X673950Y686104D03*
Y691104D03*
Y696104D03*
Y701104D03*
Y706104D03*
X687015Y677300D03*
Y672500D03*
Y667700D03*
Y662900D03*
X729722Y755280D03*
X719722D03*
X709722D03*
X699722D03*
X689722D03*
X679722D03*
X669722D03*
X674722D03*
X684722D03*
X694722D03*
X704722D03*
X714722D03*
X724722D03*
X734722D03*
X780100Y8500D03*
X775100D03*
X770100D03*
X765100D03*
X760100D03*
X755100D03*
X750100D03*
X745100D03*
X787895D03*
X797895D03*
X792895D03*
X744960Y197430D03*
X754000Y172700D03*
Y177500D03*
X797500Y226000D03*
X791140Y247740D03*
X753479Y207914D03*
X752700Y214100D03*
X744768Y300864D03*
X748100Y281300D03*
X748000Y288000D03*
X741100Y307400D03*
X739100Y302126D03*
X736952Y311391D03*
X743800Y278600D03*
X736800Y278300D03*
X798359Y351659D03*
X795193Y355540D03*
X791786Y359001D03*
X735484Y429378D03*
Y434178D03*
Y462978D03*
Y458178D03*
Y453378D03*
Y448578D03*
Y443778D03*
Y438978D03*
X798000Y459300D03*
X740300Y427100D03*
Y431900D03*
X751100Y405400D03*
X755900D03*
X760700D03*
X765500D03*
X770300D03*
X775100D03*
X740300Y446300D03*
Y441500D03*
Y436700D03*
X790600Y458000D03*
X781000D03*
X785800D03*
X776200D03*
X789500Y405400D03*
X784700D03*
X779900D03*
X750000Y427100D03*
X754800D03*
X783800Y436000D03*
X779000D03*
X793400D03*
X788600D03*
X788400Y427100D03*
X783600D03*
X778800D03*
X774200Y436000D03*
X774000Y427100D03*
X769200D03*
X764400D03*
X759600D03*
X735484Y467778D03*
X799722Y755280D03*
X789722D03*
X779722D03*
X769722D03*
X759722D03*
X749722D03*
X739722D03*
X744722D03*
X754722D03*
X764722D03*
X774722D03*
X784722D03*
X794722D03*
X807895Y8500D03*
X817895D03*
X827895D03*
X837895D03*
X847895D03*
X857895D03*
X862895D03*
X852895D03*
X842895D03*
X832895D03*
X822895D03*
X812895D03*
X802895D03*
X815670Y242890D03*
X820100Y252600D03*
X802000Y232500D03*
X823100Y225400D03*
X811000Y234300D03*
X816400Y235900D03*
X807000Y230500D03*
X812630Y249229D03*
X828781Y231061D03*
X806400Y257300D03*
X842600Y339400D03*
X841100Y332300D03*
X826993Y358840D03*
X821502Y358356D03*
X827145Y363638D03*
X821653Y363488D03*
X826900Y332500D03*
X825300Y339900D03*
X825100Y347300D03*
X828100Y352900D03*
X809792Y379122D03*
X814592D03*
X809792Y374322D03*
X814592D03*
X842900Y347200D03*
X840800Y352800D03*
X828000Y459300D03*
X823200D03*
X832800D03*
X818400D03*
X807600D03*
X802800D03*
X812400D03*
X864727Y398458D03*
X804300Y436500D03*
X813900D03*
X809100D03*
X818700D03*
X823500D03*
X830100Y501500D03*
X839700D03*
X834900D03*
X827000Y516000D03*
X832000D03*
Y521000D03*
X827000D03*
X843900Y464000D03*
X848700Y465200D03*
Y470600D03*
X849722Y755280D03*
X839722D03*
X829722D03*
X819722D03*
X809722D03*
X804722D03*
X814722D03*
X824722D03*
X834722D03*
X844722D03*
X854722D03*
X867895Y8500D03*
X877895D03*
X887895D03*
X897895D03*
X907895D03*
X916697Y19698D03*
Y29698D03*
Y39698D03*
Y49698D03*
Y59698D03*
Y69698D03*
Y64698D03*
Y54698D03*
Y44698D03*
Y34698D03*
Y24698D03*
Y14698D03*
X912895Y8500D03*
X902895D03*
X892895D03*
X882895D03*
X872895D03*
X916697Y79698D03*
Y89698D03*
Y99698D03*
Y109698D03*
Y119698D03*
Y129698D03*
Y134698D03*
Y124698D03*
Y114698D03*
Y104698D03*
Y94698D03*
Y84698D03*
Y74698D03*
Y139698D03*
Y149698D03*
Y159698D03*
Y169698D03*
Y179698D03*
Y189698D03*
Y199698D03*
Y194698D03*
Y184698D03*
Y174698D03*
Y164698D03*
Y154698D03*
Y144698D03*
Y209698D03*
Y219698D03*
Y229698D03*
Y239698D03*
Y249698D03*
Y259698D03*
Y264698D03*
Y254698D03*
Y244698D03*
Y234698D03*
Y224698D03*
Y214698D03*
Y204698D03*
Y269698D03*
Y279698D03*
Y289698D03*
Y299698D03*
Y309698D03*
Y319698D03*
Y329698D03*
Y324698D03*
Y314698D03*
Y304698D03*
Y294698D03*
Y284698D03*
Y274698D03*
Y339698D03*
Y349698D03*
Y359698D03*
Y369698D03*
Y379698D03*
Y389698D03*
Y394698D03*
Y384698D03*
Y374698D03*
Y364698D03*
Y354698D03*
Y344698D03*
Y334698D03*
X881147Y394517D03*
X916697Y399698D03*
Y409698D03*
Y419698D03*
Y429698D03*
Y439698D03*
Y449698D03*
Y459698D03*
Y454698D03*
Y444698D03*
Y434698D03*
Y424698D03*
Y414698D03*
Y404698D03*
X874727Y398458D03*
X869727D03*
X880887Y399474D03*
X916697Y469698D03*
Y479698D03*
Y489698D03*
Y499698D03*
Y509698D03*
Y519698D03*
Y524698D03*
Y514698D03*
Y504698D03*
Y494698D03*
Y484698D03*
Y474698D03*
Y464698D03*
Y529698D03*
Y539698D03*
Y549698D03*
Y559698D03*
Y569698D03*
Y579698D03*
Y589698D03*
Y584698D03*
Y574698D03*
Y564698D03*
Y554698D03*
Y544698D03*
Y534698D03*
Y599698D03*
Y609698D03*
Y619698D03*
Y629698D03*
Y639698D03*
Y649698D03*
Y659698D03*
Y654698D03*
Y644698D03*
Y634698D03*
Y624698D03*
Y614698D03*
Y604698D03*
Y594698D03*
Y669698D03*
Y679698D03*
Y689698D03*
Y699698D03*
Y709698D03*
Y719698D03*
Y714698D03*
Y704698D03*
Y694698D03*
Y684698D03*
Y674698D03*
Y664698D03*
X914700Y726100D03*
X912436Y730603D03*
X910200Y735300D03*
X907564Y739747D03*
X905500Y744400D03*
X903192Y748791D03*
X900800Y753700D03*
X894722Y755280D03*
G54D20*
X65400Y549600D03*
X78231Y565999D03*
X92870Y568015D03*
X97113Y567986D03*
X100619Y567985D03*
X137100Y595600D03*
X133600D03*
X207500Y499180D03*
X252670Y624037D03*
X224346Y625595D03*
X245200Y691900D03*
X365400Y511600D03*
X367600Y705500D03*
X645000Y556500D03*
X721400Y281800D03*
X790360Y243000D03*
G54D11*
X80708Y44292D03*
X61024Y34449D03*
X33464D03*
X56102Y24606D03*
X38386D03*
X108268Y44292D03*
X103346Y34449D03*
X85630D03*
X590300Y574400D03*
X600300D03*
X610300D03*
G54D30*
X110300Y497300D03*
X162335Y481762D03*
X148716Y570304D03*
X171979Y583387D03*
X175660Y611180D03*
Y607480D03*
X203750Y633450D03*
X263205Y549594D03*
X232800Y633900D03*
X356000Y541400D03*
X365489Y554000D03*
X557200Y64700D03*
X581000Y77400D03*
X662200Y421500D03*
Y417500D03*
Y413500D03*
Y426000D03*
X723668Y294464D03*
X731168D03*
X787150Y234770D03*
X753500Y262350D03*
X787300Y224400D03*
X787150Y231350D03*
Y227900D03*
X746000Y262350D03*
X744650Y268900D03*
X738668Y294464D03*
X752450Y268900D03*
G54D21*
X54100Y586350D03*
X46500D03*
X100100Y705700D03*
X92500D03*
X184910Y622020D03*
X192510D03*
X178430Y621990D03*
X170830D03*
X219840Y615320D03*
X227440D03*
X328622Y184294D03*
X321022D03*
X328648Y191994D03*
X321048D03*
X310449Y221407D03*
X318049D03*
X310479Y229157D03*
X318079D03*
X664600Y301300D03*
X622300Y481000D03*
X614700D03*
X622300Y473000D03*
X614700D03*
X731600Y261150D03*
X672200Y301300D03*
X721300Y456900D03*
X728900D03*
X721300Y464700D03*
X728900D03*
X697376Y554429D03*
X704976D03*
X781600Y196000D03*
X774000D03*
X795837Y196018D03*
X788237D03*
X761300Y199300D03*
X753700D03*
X761300Y191500D03*
X753700D03*
X773700Y188200D03*
X781300D03*
X788237Y188218D03*
X795837D03*
X758800Y174900D03*
X766400D03*
X772610Y241950D03*
X780210D03*
X739200Y261150D03*
X810162Y195983D03*
X802562D03*
Y188083D03*
X810162D03*
X830200Y339000D03*
X837800D03*
Y347000D03*
X830200D03*
X835600Y481500D03*
X843200D03*
G54D12*
G01X126850Y485090D02*
X132136D01*
X133152Y484074D01*
G01X253583Y653829D02*
X248912Y658500D01*
X233870D01*
X231664Y656294D01*
X213314D01*
X213220Y656200D01*
X193556D01*
X191401Y654045D01*
X178308D01*
X178203Y653940D01*
X178069D01*
X170553Y646424D01*
X170488D01*
X170486Y646422D01*
X125878D01*
X120500Y651800D01*
G01X125376Y701124D02*
X118998D01*
G01X106879Y707245D02*
X109200Y704924D01*
Y704630D01*
X112706Y701124D01*
X118998D01*
G01X163349Y702715D02*
X154463D01*
X153088Y701340D01*
X129302D01*
X124593Y706049D01*
X117777D01*
X115598Y708228D01*
G01X106355Y710745D02*
X113081D01*
X115598Y708228D01*
G01X119849Y709715D02*
X116319Y713245D01*
X109478D01*
G01X102700Y712200D02*
X103745Y713245D01*
X109478D01*
G01X100100Y705700D02*
Y709600D01*
X102700Y712200D01*
G01X156299Y570866D02*
X155737Y570304D01*
X152266D01*
G01X205020Y608690D02*
Y606865D01*
X203605Y605450D01*
G01X200610Y639611D02*
X201059D01*
X203400Y637270D01*
X203720D01*
X203740Y637250D01*
G01X200210Y599340D02*
Y596246D01*
X200393Y596063D01*
G01X203800Y633450D02*
X202210D01*
X200560Y635100D01*
G01X197191Y636638D02*
X199022D01*
X200560Y635100D01*
G01X203650Y641270D02*
X195900Y649020D01*
Y649350D01*
G01X151949Y691715D02*
X157469Y697235D01*
X162098D01*
G01X175233Y704382D02*
X172605D01*
X165458Y697235D01*
X162098D01*
G01X169070Y696220D02*
X178320D01*
X184286Y702186D01*
X262514D01*
X264700Y700000D01*
G01X200400Y694700D02*
X204800Y699100D01*
X254900D01*
X256788Y697212D01*
G01X222600Y503500D02*
X221870Y504230D01*
X219160D01*
G01X261900Y591300D02*
X264500D01*
X265859Y589941D01*
Y587813D01*
G01X229063Y638560D02*
X232090D01*
X232750Y637900D01*
G01X225558Y637894D02*
X226224Y638560D01*
X229063D01*
G01X225569Y634188D02*
X226262Y634881D01*
X229137D01*
G01X232850Y633900D02*
X231869Y634881D01*
X229137D01*
G01X245100Y647200D02*
X241150D01*
X236250Y642300D01*
G01X272200Y648550D02*
X270010Y650740D01*
X256672D01*
X253583Y653829D01*
G01X245200Y691850D02*
X243550D01*
X242000Y693400D01*
G01X256788Y697212D02*
X258675Y695325D01*
X277925D01*
X282300Y699700D01*
Y700100D01*
G01X335982Y390874D02*
X339101Y393993D01*
X340157D01*
G01X321976Y505750D02*
X320650Y507076D01*
Y509440D01*
G01X308687Y519193D02*
X310283Y520789D01*
X314370D01*
G01D02*
X316726D01*
X320650Y516865D01*
Y514560D01*
G01X325900Y678500D02*
Y678600D01*
X325250Y679250D01*
Y681900D01*
G01X315290Y681920D02*
X317280D01*
X318400Y680800D01*
Y678400D01*
G01X398983Y706749D02*
X404764Y700968D01*
Y470473D01*
X402988Y468697D01*
Y176420D01*
X408106Y171302D01*
Y154866D01*
X400430Y147190D01*
G01X400064Y652598D02*
X402264Y650398D01*
Y474217D01*
X399562Y471515D01*
Y362985D01*
X386537Y349960D01*
X370760D01*
X365200Y344400D01*
G01X365400Y511550D02*
X367850D01*
X369000Y512700D01*
G01X369350Y517340D02*
Y513050D01*
X369000Y512700D01*
G01X368721Y525271D02*
Y525283D01*
X364930Y529074D01*
Y529840D01*
G01X363008Y547309D02*
X362627Y546928D01*
Y541523D01*
X363550Y540600D01*
G01X380000Y601850D02*
X382050D01*
X383300Y600600D01*
G01X384814Y629080D02*
Y633126D01*
X384410Y633530D01*
G01X350500Y647600D02*
Y646400D01*
X354000Y642900D01*
Y637900D01*
G01X346465Y703185D02*
X347215D01*
X349100Y701300D01*
Y699930D01*
X354470Y694560D01*
G01X348500Y660420D02*
X353856D01*
X354102Y660666D01*
G01X371750Y689500D02*
Y691250D01*
X369600Y693400D01*
G01X351100Y712100D02*
X354570Y708630D01*
Y707160D01*
G01X578900Y82500D02*
X578300Y81900D01*
X569182D01*
X567482Y80200D01*
X550382D01*
X548410Y82172D01*
X531578D01*
X502450Y111300D01*
X490100D01*
G01X557750Y69940D02*
Y68500D01*
X558550Y67700D01*
X558551D01*
X560750Y65501D01*
Y64700D01*
G01X601500Y368050D02*
Y363600D01*
G01X606626Y354723D02*
X606549Y354800D01*
X602900D01*
X601500Y356200D01*
Y359150D01*
G01X629400Y217300D02*
X629900Y216800D01*
Y211250D01*
G01X654300Y504100D02*
X653300Y505100D01*
Y531795D01*
X648800Y536295D01*
Y546000D01*
G01X638660Y568043D02*
X636000Y565383D01*
Y560899D01*
X633470Y558369D01*
Y555133D01*
X604000Y525663D01*
Y501806D01*
G01X613000Y463000D02*
X607000D01*
X604000Y466000D01*
Y501806D01*
G01X632800Y561600D02*
Y561503D01*
X630970Y559673D01*
Y557353D01*
X627408Y553791D01*
G01X620160Y544793D02*
Y546543D01*
X627408Y553791D01*
G01X645000Y556450D02*
X643850Y557600D01*
X640400D01*
G01D02*
X635970D01*
G01X645000Y552950D02*
X648800Y549150D01*
Y546000D01*
G01X726100Y231460D02*
Y229444D01*
X727594Y227950D01*
G01X726310Y225060D02*
Y226666D01*
X727594Y227950D01*
G01X730900Y284210D02*
Y281686D01*
X730710Y281496D01*
G01X721400Y281750D02*
X724156D01*
X724410Y281496D01*
G01X734300Y496000D02*
X733500D01*
X730600Y493100D01*
G01X732140Y487233D02*
X727039Y492334D01*
X716078D01*
G01X710000Y549100D02*
Y549711D01*
X716442Y556153D01*
Y560260D01*
G01X714800Y567956D02*
X716442Y566314D01*
Y560260D01*
G01X697376Y554429D02*
Y558204D01*
X699472Y560300D01*
G01X705676Y562429D02*
X701601D01*
X699472Y560300D01*
G01X697200Y548100D02*
X697376Y548276D01*
Y554429D01*
G01X768529Y199404D02*
Y203914D01*
X768579Y203964D01*
G01X781580Y261940D02*
X782258Y262618D01*
X784258D01*
G01D02*
X786352D01*
X786880Y262090D01*
G01X749150Y208500D02*
Y215500D01*
X745850Y218800D01*
G01X777700Y309500D02*
X777900Y309300D01*
X780300D01*
G01X788493Y285800D02*
Y286702D01*
X787400Y287795D01*
G01X788220Y283030D02*
X788100Y282910D01*
Y282200D01*
X787400Y281500D01*
Y280500D01*
G01X770800Y299900D02*
Y298097D01*
X771654Y297243D01*
G01X790200Y269000D02*
Y271734D01*
X790519Y272053D01*
G01X790800Y295500D02*
X789145D01*
X787402Y297243D01*
G01X787400Y280500D02*
Y278373D01*
X787419Y278354D01*
G01X752000Y286000D02*
X750923D01*
X749593Y284670D01*
G01X758408Y284964D02*
Y287145D01*
X759073Y287810D01*
G01X778090Y284820D02*
X777915Y284645D01*
Y281496D01*
G01X790800Y297700D02*
Y300132D01*
X790526Y300406D01*
G01X760608Y284964D02*
Y283052D01*
X759070Y281514D01*
G01X777700Y307300D02*
Y304868D01*
X777790Y304778D01*
G01X770800Y302100D02*
Y303432D01*
X769768Y304464D01*
G01X786020Y283030D02*
X785217Y282227D01*
X785012D01*
X784249Y281464D01*
G01X803800Y273800D02*
X800920D01*
X800720Y274000D01*
X798768D01*
X796832Y272064D01*
G01X803100Y292800D02*
X802392Y293508D01*
X799350D01*
X796839Y290997D01*
Y290934D01*
G01X799400Y307000D02*
Y306856D01*
X796875Y304331D01*
G01X789600Y280500D02*
Y279335D01*
X790551Y278384D01*
G01X788000Y269000D02*
Y271486D01*
X787426Y272060D01*
G01X786293Y285800D02*
X784299Y287794D01*
X784251D01*
G01X752000Y288200D02*
X755502D01*
X755898Y287804D01*
G01X750600Y488850D02*
X752950D01*
X755100Y486700D01*
G01X759900Y486600D02*
X767900D01*
X770900Y483600D01*
X774700D01*
G01X755100Y486700D02*
X755200Y486600D01*
X759900D01*
G01X740100Y491534D02*
Y495200D01*
X739300Y496000D01*
G01D02*
X741500Y498200D01*
X742300D01*
G01X735600Y491534D02*
Y494700D01*
X734300Y496000D01*
G01X755100Y474900D02*
Y481900D01*
G01D02*
X756100Y482900D01*
X759000D01*
G01X754883Y498500D02*
X751690D01*
X750600Y497410D01*
Y497400D01*
G01X754883Y498500D02*
X756555D01*
X756565Y498510D01*
X758073D01*
X759169Y497414D01*
G01X750600Y497400D02*
Y492350D01*
G01X817800Y479600D02*
X808600D01*
X792600Y495600D01*
X781900D01*
X780750Y496750D01*
G01X804100Y479200D02*
X790200Y493100D01*
X781600D01*
X781050Y492550D01*
G01X803100Y290600D02*
X800343D01*
X799999Y290944D01*
G01X803668Y270664D02*
X803604Y270600D01*
X801432D01*
X799974Y272058D01*
G01X806000Y273800D02*
Y273500D01*
X803668Y271168D01*
Y270664D01*
G01X801600Y309500D02*
Y307000D01*
G01D02*
Y305400D01*
X803300Y303700D01*
G01X799400Y309500D02*
Y307000D01*
G01X805868Y270664D02*
X809479D01*
X810079Y271264D01*
G01X817800Y479600D02*
X821700D01*
X839800Y461500D01*
X891757D01*
X900497Y452760D01*
Y418293D01*
X897371Y415167D01*
Y340935D01*
X872636Y316200D01*
X852863D01*
X851400Y317663D01*
Y317664D01*
X847764Y321300D01*
X839400D01*
X829300Y311200D01*
X823700D01*
X822900Y310400D01*
X817950D01*
G01Y314600D02*
X822900D01*
X823800Y313700D01*
X828264D01*
X838364Y323800D01*
X848800D01*
X853900Y318700D01*
X871600D01*
X894871Y341971D01*
Y416203D01*
X897384Y418716D01*
Y452337D01*
X890721Y459000D01*
X838764D01*
X820782Y476982D01*
X806318D01*
X804100Y479200D01*
X18700Y54650D03*
X89764Y238386D03*
X90157Y413583D03*
X209189Y37075D03*
Y383483D03*
X201801Y684252D03*
X225601D03*
X309055Y157677D03*
X305906Y182874D03*
Y388386D03*
X309252Y413583D03*
X488838Y137225D03*
Y164744D03*
X489331Y245605D03*
Y698924D03*
X652756Y180000D03*
X865353Y332598D03*
X901000Y21400D03*
X902500Y676000D03*
G54D31*
X140702Y489161D03*
X183100Y503100D03*
X179200Y525000D03*
X170800Y503100D03*
X179000D03*
X155000Y496400D03*
X166700Y503100D03*
X187300Y503000D03*
X166861Y490920D03*
X146300Y496100D03*
X150500Y496380D03*
X191000Y532600D03*
X202700Y532700D03*
X206800Y532580D03*
X205020Y608740D03*
X197191Y633188D03*
X192911Y633248D03*
X215658Y483533D03*
X266816Y561137D03*
X270836Y561119D03*
X246145Y557918D03*
X273490Y584402D03*
X228102Y529442D03*
X210900Y532600D03*
X335962Y702196D03*
X352480Y586164D03*
X365400Y572700D03*
X360300Y558400D03*
X347500Y706300D03*
X345654Y696615D03*
X375500Y704300D03*
X456400Y54400D03*
X512290Y54273D03*
X500411Y51865D03*
X490653Y60737D03*
X629500Y190800D03*
X656665Y298466D03*
X652465Y298566D03*
X732230Y307869D03*
X708300Y449300D03*
X750600Y488900D03*
X828800Y235900D03*
X815726Y363856D03*
G54D40*
X105474Y535824D03*
X181148Y568251D03*
X192089Y582625D03*
X185200Y559200D03*
X190680Y615540D03*
X222550Y609150D03*
X384614Y629080D03*
X836800Y332500D03*
G54D22*
X78524Y558398D03*
X78525Y554363D03*
X117930Y499550D03*
X98076Y560166D03*
X98044Y555240D03*
X149700Y460200D03*
X158530Y510140D03*
X173900Y517000D03*
X149565Y481057D03*
X149685Y468562D03*
X153988Y522134D03*
X153958Y517677D03*
X172402Y574058D03*
X148354Y588802D03*
X197490Y611700D03*
X169493Y635303D03*
X196760Y599340D03*
X184250Y607360D03*
X203790Y637250D03*
X197916Y620590D03*
X148057Y602562D03*
X224409Y558053D03*
X265912Y583809D03*
X224300Y585900D03*
X224375Y576816D03*
X224000Y571900D03*
X223200Y593200D03*
X243400Y531240D03*
X242200Y543100D03*
X245800Y606260D03*
X238150Y610860D03*
X211700Y642200D03*
X246365Y594250D03*
X235362Y606422D03*
X223200Y597200D03*
X232800Y637900D03*
X235410Y602160D03*
X232800Y642300D03*
X222092Y642006D03*
X317300Y552900D03*
X312700Y573000D03*
X308950Y658050D03*
X316500Y658100D03*
X338200Y696100D03*
X344117Y575841D03*
X356096Y545220D03*
X363600Y540600D03*
X375716Y620503D03*
X362500Y664200D03*
X375757Y695203D03*
X489779Y30448D03*
X507300Y65000D03*
X489800Y38500D03*
X479900Y58900D03*
Y62900D03*
X613286Y367271D03*
X707652Y261999D03*
X745700Y208500D03*
X821300Y240200D03*
X820100Y248200D03*
X821268Y235964D03*
X821300Y244200D03*
X811000Y257800D03*
X814500Y310400D03*
X832300Y353000D03*
G54D13*
G01X-13131Y-65072D02*
Y-145072D01*
G01D02*
X1244069D01*
G01X-29131Y-65072D02*
Y-33072D01*
G01X-13131Y-65072D02*
X1244069D01*
G01X-13131Y-100572D02*
X1244069D01*
G01X-17131Y-49072D02*
G02I-12000J0D01*
G01X-22281D02*
G02I-6850J0D01*
G01X-13131D02*
X-45131D01*
G01X31100Y458733D02*
X43833Y446000D01*
X121500D01*
X126206Y441294D01*
X213832D01*
X215388Y442850D01*
X225640D01*
X240090Y457300D01*
X261800D01*
X264400Y454700D01*
X273600D01*
X280400Y447900D01*
X295061D01*
X301920Y441041D01*
X352595D01*
X372009Y421627D01*
Y378507D01*
X372491Y378025D01*
G01X26576Y457406D02*
X42482Y441500D01*
X120050D01*
X123756Y437794D01*
X215282D01*
X216838Y439350D01*
X247450D01*
X251700Y443600D01*
G01X49356Y521269D02*
X53524D01*
G01X49356Y526995D02*
X53524D01*
G01X75405Y517527D02*
Y521695D01*
G01X69778Y517527D02*
Y521695D01*
G01X64151Y517527D02*
Y521695D01*
G01X65400Y549550D02*
X63219D01*
X62276Y550493D01*
G01X65400Y546050D02*
X61750D01*
X61100Y546700D01*
G01X64350Y582700D02*
X67239D01*
X67852Y583313D01*
G01X74400Y556700D02*
X76098Y558398D01*
X78474D01*
G01X78231Y562449D02*
Y558641D01*
X78474Y558398D01*
G01X78475Y554363D02*
X76737D01*
X74400Y556700D01*
G01X49356Y543876D02*
X52408D01*
G01X49435Y549526D02*
X52603D01*
G01X49435Y555153D02*
X52485D01*
G01X49435Y560879D02*
X53300D01*
G01X49356Y532622D02*
X53524D01*
G01X49356Y538249D02*
X52606D01*
X52613Y538242D01*
G01X76100Y697100D02*
X80450Y692750D01*
X102500D01*
X108319Y686931D01*
X175159D01*
X179160Y682930D01*
X196170D01*
X199150Y679950D01*
X231300D01*
X236335Y674915D01*
X237509D01*
G01X135012Y510200D02*
X136702Y508510D01*
Y492611D01*
G01X107100Y497300D02*
X110350D01*
G01X113850D02*
X115100D01*
X117200Y495200D01*
G01X140702Y492611D02*
Y507312D01*
G01D02*
X141980Y508590D01*
G01X92286Y517527D02*
Y521695D01*
G01X81032Y517527D02*
Y521695D01*
G01X86659Y517527D02*
Y521695D01*
G01X97913Y517527D02*
Y521695D01*
G01X146750Y584699D02*
X143954D01*
X141189Y587464D01*
Y590537D01*
G01X96287Y576449D02*
X93613D01*
X93048Y577014D01*
G01X100180Y576452D02*
X96290D01*
X96287Y576449D01*
G01X138350Y584250D02*
X140500Y582100D01*
X149731D01*
X151213Y580618D01*
X151282D01*
X151350Y580550D01*
Y574788D01*
X153198Y572940D01*
X154650D01*
G01X137100Y592050D02*
Y585500D01*
X138350Y584250D01*
G01X133600Y592050D02*
X137100D01*
G01X122600Y589800D02*
X127600D01*
X129100Y591300D01*
G01X133600Y592050D02*
X129850D01*
X129100Y591300D01*
G01X97994Y555240D02*
X96638D01*
X94720Y557158D01*
G01X99674Y535824D02*
X98071D01*
X96371Y534124D01*
G01X116900Y597500D02*
X113200Y601200D01*
Y632800D01*
X118500Y638100D01*
G01X203150Y653100D02*
X194699D01*
X194401Y652802D01*
Y652801D01*
X192645Y651045D01*
X192644D01*
X192499Y650900D01*
X179272D01*
X171796Y643424D01*
X171731D01*
X171729Y643422D01*
X151645D01*
X149401Y641178D01*
Y641124D01*
X146977Y638700D01*
X143550D01*
X140650Y641600D01*
X127400D01*
X119000Y633200D01*
G01X83170Y719500D02*
X89400D01*
X96700Y712200D01*
G01X149650Y460200D02*
X146301D01*
G01X149635Y468562D02*
X146263D01*
G01X179000Y503050D02*
Y499800D01*
G01X149515Y481057D02*
X146143D01*
G01X166861Y490870D02*
X169470D01*
X170870Y492270D01*
G01X158000Y480700D02*
X159062Y481762D01*
X162385D01*
G01X211770Y491100D02*
X208840D01*
X208370Y491570D01*
G01D02*
X207500Y492440D01*
Y495630D01*
G01X183100Y503050D02*
Y499800D01*
G01X170838Y481762D02*
X165885D01*
G01X146300Y499550D02*
Y502600D01*
G01X162800Y490850D02*
X160250D01*
X158100Y493000D01*
G01X174900Y503050D02*
Y499800D01*
G01X149665Y464338D02*
X146293D01*
G01X149565Y476938D02*
X146193D01*
G01X149665Y472738D02*
X146293D01*
G01X191000Y532550D02*
X192150D01*
X193050Y531650D01*
Y531649D01*
X194396Y530303D01*
X194397D01*
X195300Y529400D01*
G01X186900Y532650D02*
X186929Y532621D01*
X190929D01*
X191000Y532550D01*
G01X201220Y552500D02*
X197773D01*
X197243Y551970D01*
G01X190930Y552000D02*
X194063D01*
X194093Y551970D01*
G01X179400Y559200D02*
X176129D01*
X175197Y558268D01*
G01X175348Y568251D02*
X172581D01*
X172047Y567717D01*
G01X185350Y635300D02*
Y643600D01*
X184967Y643983D01*
G01X187700Y607360D02*
X190540D01*
X191370Y608190D01*
G01X205490Y624780D02*
X208331D01*
X208700Y625149D01*
G01X200879Y614739D02*
X199983D01*
X197440Y612196D01*
Y611700D01*
G01X192911Y636698D02*
Y639341D01*
X193610Y640040D01*
G01X169443Y635303D02*
X169452Y635294D01*
Y629826D01*
G01X169443Y635303D02*
X168497D01*
X164800Y639000D01*
Y640200D01*
G01X160964Y717268D02*
X155832D01*
X155400Y717700D01*
G01X150849Y710215D02*
X149700Y711364D01*
Y715400D01*
G01Y723000D02*
X155564D01*
X155846Y723282D01*
G01X160964Y723268D02*
X155860D01*
X155846Y723282D01*
G01X232500Y525750D02*
X228150D01*
G01X247100Y582400D02*
X246500D01*
X245950Y582950D01*
X242100D01*
G01X247400Y589600D02*
X245100D01*
X243950Y590750D01*
X242000D01*
G01X226650Y593200D02*
X229800D01*
G01X227598Y581666D02*
X230834D01*
X230900Y581600D01*
G01X210900Y532550D02*
Y530000D01*
X211500Y529400D01*
G01X252593Y547650D02*
Y549743D01*
X253859Y551009D01*
X261840D01*
X263255Y549594D01*
G01X243650Y539000D02*
X244623D01*
X246484Y537139D01*
G01X241950Y550400D02*
X243905D01*
X245016Y551511D01*
X246611D01*
G01X227750Y585900D02*
X230400D01*
X234000Y582300D01*
X234300D01*
G01X266755Y549594D02*
X269821D01*
X270021Y549394D01*
G01X249767Y569957D02*
Y565917D01*
X249750Y565900D01*
G01X246145Y557868D02*
X250259Y553754D01*
X251446D01*
G01X241950Y558500D02*
Y554400D01*
G01Y558500D02*
X245513D01*
X246145Y557868D01*
G01X273500Y567400D02*
Y570401D01*
X270947Y572954D01*
G01X273500Y567400D02*
X272500Y566400D01*
Y566322D01*
X270836Y564658D01*
Y564569D01*
G01X249815Y594250D02*
Y590985D01*
X254300Y586500D01*
G01X273490Y587852D02*
Y590510D01*
X273400Y590600D01*
Y590902D01*
G01X227825Y576816D02*
X231184D01*
X231200Y576800D01*
G01X227450Y571900D02*
X231000D01*
G01X215100Y532550D02*
Y529600D01*
X214900Y529400D01*
G01X249750Y565900D02*
X250550Y565100D01*
X253310D01*
X254051Y564359D01*
X254532D01*
Y564300D01*
X254530D01*
G01X245743Y546963D02*
X245650Y546870D01*
Y543100D01*
G01X249782Y579067D02*
X254067D01*
X254500Y579500D01*
G01X234300Y582300D02*
X235400D01*
X236050Y582950D01*
X238100D01*
G01X228400Y564300D02*
X229978D01*
X231434Y562844D01*
G01X214650Y649500D02*
X216300D01*
X218200Y651400D01*
G01X215250Y638400D02*
X216000D01*
X218800Y635600D01*
G01X218200Y651400D02*
X216306Y653294D01*
X214558D01*
G01X218800Y635600D02*
X217700Y634500D01*
X215250D01*
G01X246500Y601500D02*
X245660Y600660D01*
X241980D01*
X240480Y602160D01*
X238860D01*
G01X248450Y609900D02*
Y609134D01*
X249250Y608334D01*
Y606260D01*
G01X241600Y610860D02*
X247490D01*
X248450Y609900D01*
G01X228149Y600094D02*
X228148D01*
X226650Y598596D01*
Y597200D01*
G01X238812Y606422D02*
X239398D01*
X240460Y605360D01*
X241970D01*
X242710Y604620D01*
G01X226471Y649129D02*
X225613Y648271D01*
Y644594D01*
X225542Y644523D01*
Y642006D01*
G01X215150Y642200D02*
Y645350D01*
X215606Y645806D01*
G01X245200Y688350D02*
X253750D01*
X254800Y689400D01*
G01X339331Y42851D02*
Y49803D01*
G01D02*
Y56755D01*
G01X334929Y49803D02*
X339331D01*
G01D02*
X343733D01*
G01X339331Y86327D02*
Y91929D01*
G01D02*
Y97531D01*
G01X334929Y91929D02*
X339331D01*
G01D02*
X343733D01*
G01X305700Y197600D02*
X304500D01*
X296020Y206080D01*
Y368581D01*
X303439Y376000D01*
X315500D01*
X317800Y373700D01*
X323300D01*
X324200Y374600D01*
Y380600D01*
X325800Y382200D01*
X329300D01*
X335600Y375900D01*
X339374D01*
X343400Y371874D01*
X360827D01*
X366331Y366370D01*
X371435D01*
X382000Y376935D01*
Y430000D01*
X370900Y441100D01*
Y442700D01*
X360100Y453500D01*
G01X305862Y210014D02*
X306986D01*
X311086Y205914D01*
X330390D01*
X333838Y202466D01*
X337285D01*
X339479Y204660D01*
X339793Y206277D01*
Y210963D01*
X334882Y215874D01*
G01X327174Y385868D02*
X330832D01*
X334000Y382700D01*
G01X307900Y510750D02*
X307364Y510214D01*
Y505750D01*
G01X307900Y514250D02*
X306250D01*
X304800Y512800D01*
G01X310100Y514250D02*
X307900D01*
G01X352279Y580294D02*
X353347Y579226D01*
Y557113D01*
X344340Y548106D01*
Y534722D01*
X340342Y530724D01*
Y525419D01*
X344196Y521565D01*
Y517519D01*
X349638Y512077D01*
Y505738D01*
X344500Y500600D01*
Y500300D01*
G01X340500Y711750D02*
Y712200D01*
X336637Y716063D01*
X316465D01*
G01X360669Y44201D02*
Y49803D01*
G01D02*
Y55405D01*
G01X356267Y49803D02*
X360669D01*
G01D02*
X365071D01*
G01X360669Y84977D02*
Y91929D01*
G01D02*
Y98881D01*
G01X356267Y91929D02*
X360669D01*
G01D02*
X365071D01*
G01X349182Y381324D02*
X346032D01*
X345582Y380874D01*
G01X356600Y520850D02*
X353750Y520950D01*
X353300Y521400D01*
G01X351900Y528850D02*
Y527243D01*
X354143Y525000D01*
X356050D01*
X356600Y524350D01*
G01X365400Y508050D02*
X368650D01*
X369300Y508700D01*
G01X369500Y576150D02*
X369557Y576207D01*
X372600D01*
G01X352480Y586114D02*
X352230Y585864D01*
X348564D01*
X348314Y585614D01*
G01D02*
X346618Y587310D01*
X345244D01*
G01X366350Y567213D02*
X370844D01*
X371227Y566830D01*
G01X356050Y541400D02*
X352400D01*
X351600Y540600D01*
G01X363008Y547309D02*
X363539D01*
X365539Y549309D01*
Y554000D01*
G01X372600Y576207D02*
X373293D01*
X374750Y574750D01*
X378500D01*
G01X356480Y586890D02*
Y583792D01*
X355012Y582324D01*
G01X384950Y560496D02*
X385799Y561345D01*
Y574201D01*
X383000Y577000D01*
G01D02*
X382100D01*
X380850Y578250D01*
X378500D01*
G01X362700Y551200D02*
X361800D01*
X359546Y548946D01*
Y545220D01*
G01D02*
Y542855D01*
X359550Y542851D01*
Y541400D01*
G01X347900Y539800D02*
Y545200D01*
X360300Y557600D01*
Y558350D01*
G01X365400Y576150D02*
X363550D01*
X362100Y574700D01*
G01X347567Y575841D02*
X349000Y577274D01*
Y581360D01*
G01X348600Y643500D02*
Y643200D01*
X349200Y642600D01*
Y637900D01*
G01X367620Y599564D02*
X362136D01*
X361800Y599900D01*
G01X375600Y598400D02*
X374436Y599564D01*
X367620D01*
G01X351200Y612600D02*
Y602490D01*
X352720Y600970D01*
G01D02*
X353590Y600100D01*
X361600D01*
X361800Y599900D01*
G01X367113Y626307D02*
X369034D01*
X369309Y626032D01*
X371034D01*
G01D02*
Y628252D01*
X372408Y629626D01*
G01X391350Y700700D02*
Y698870D01*
X392720Y697500D01*
G01X367600Y705450D02*
Y709700D01*
X364200Y713100D01*
G01X388870Y706140D02*
Y703171D01*
X387850Y702151D01*
Y700700D01*
G01D02*
X384302D01*
X384220Y700618D01*
G01X367600Y701950D02*
Y696800D01*
G01X368250Y689500D02*
Y690507D01*
X366600Y692157D01*
Y695343D01*
X367600Y696343D01*
Y696800D01*
G01X456569Y-65072D02*
Y-145072D01*
G01X459950Y61900D02*
Y58000D01*
G01D02*
X461900Y56050D01*
X472175D01*
X474050Y57925D01*
G01X445900Y31700D02*
X440825D01*
X439554Y30429D01*
G01X428001Y25269D02*
Y49928D01*
X423300Y54629D01*
Y63174D01*
X415211Y71263D01*
G01X486400Y74700D02*
X486331Y74631D01*
X478831D01*
X476910Y72710D01*
X442737D01*
X433400Y63373D01*
G01X477943Y41765D02*
X482258D01*
X482693Y42200D01*
G01X478500Y25500D02*
Y19775D01*
G01X594069Y-65072D02*
Y-145072D01*
G01X557250Y64700D02*
X552710D01*
X552540Y64530D01*
G01X588749Y65000D02*
Y62300D01*
X591000Y60049D01*
Y53900D01*
X605600Y39300D01*
X660051D01*
X662051Y37300D01*
Y37299D01*
X666535Y32815D01*
Y26149D01*
G01X584550Y77400D02*
X589600Y72350D01*
Y65851D01*
X588749Y65000D01*
G01X560750Y64700D02*
Y48750D01*
X559600Y47600D01*
G01X581050Y77400D02*
X579850Y78600D01*
X577100D01*
G01X584550Y80750D02*
Y77400D01*
G01X596077Y369579D02*
X600457Y373959D01*
X630700D01*
X630703Y373956D01*
X636900D01*
X637000Y373856D01*
G01X647500Y199850D02*
X644100D01*
G01X629500Y190750D02*
Y187500D01*
G01X634000Y190750D02*
Y187500D01*
G01X644100Y203350D02*
X647500D01*
G01X648698Y296339D02*
Y292902D01*
X648700Y292900D01*
G01X881147Y394517D02*
X869730Y383100D01*
X678190D01*
X655942Y360852D01*
X641952D01*
X618832Y337732D01*
X613825D01*
X609200Y333107D01*
Y330400D01*
G01X664600Y301300D02*
Y306100D01*
G01X613250Y358900D02*
Y356850D01*
X611200Y354800D01*
X610300D01*
G01X608600Y362600D02*
X609750Y361450D01*
Y358900D01*
G01X637000Y373856D02*
X637100Y373956D01*
X658444D01*
X659300Y373100D01*
G01X618600Y364375D02*
X618650D01*
X617750Y365275D01*
Y365278D01*
X616736Y366292D01*
Y367271D01*
G01X709069Y-65072D02*
Y-145072D01*
G01X730900Y191250D02*
X731100Y191050D01*
Y186800D01*
X732000Y185900D01*
G01X670200Y199850D02*
X673350D01*
X674300Y198900D01*
G01X704579Y258164D02*
X704779Y257964D01*
X708929D01*
G01X722879Y237714D02*
Y236371D01*
X724410Y234840D01*
Y234252D01*
G01X723420Y243700D02*
X723550Y243570D01*
Y241657D01*
X723661Y241546D01*
Y241300D01*
X724410Y240551D01*
G01X723190Y249850D02*
Y248420D01*
X724410Y247200D01*
Y246850D01*
G01X722900Y256550D02*
Y254905D01*
X723660Y254145D01*
Y253900D01*
X724410Y253150D01*
G01X722600Y231460D02*
Y229763D01*
X724410Y227953D01*
G01X722810Y225060D02*
Y226353D01*
X724410Y227953D01*
G01Y265748D02*
X723510Y266648D01*
Y268305D01*
X723113Y268702D01*
G01X722750Y262300D02*
Y263627D01*
X724410Y265287D01*
Y265748D01*
G01X707602Y261999D02*
X704614D01*
X704579Y261964D01*
G01X731218Y294464D02*
Y291454D01*
X730708Y290944D01*
G01X723718Y294464D02*
Y291635D01*
X724409Y290944D01*
G01X733857D02*
Y293603D01*
X734718Y294464D01*
G01X727218D02*
Y291284D01*
X727558Y290944D01*
G01X732230Y311319D02*
Y312970D01*
X730300Y314900D01*
G01X724410Y272047D02*
Y274460D01*
X725150Y275200D01*
G01X721400Y278250D02*
X724314D01*
X724410Y278346D01*
G01X725080Y287930D02*
X724580Y287430D01*
Y284815D01*
X724410Y284645D01*
G01X727400Y284210D02*
X724845D01*
X724410Y284645D01*
G01X669950Y307400D02*
Y310950D01*
G01X708300Y449250D02*
X708150Y449400D01*
X704100D01*
X699900Y453600D01*
G01X777600Y512200D02*
X776600Y511200D01*
X741300D01*
X726600Y496500D01*
X716350D01*
X712100Y492250D01*
Y474000D01*
X691950Y453850D01*
X690550D01*
G01X703440Y548820D02*
X704976Y550356D01*
Y554429D01*
G01X705176Y593429D02*
X709186D01*
X711256Y595499D01*
G01X723369Y599835D02*
X723676Y599528D01*
Y586441D01*
X729005Y581112D01*
Y551455D01*
X706150Y528600D01*
X697800D01*
X697200Y529200D01*
G01X693899Y607558D02*
Y603101D01*
X694000Y603000D01*
G01D02*
Y597900D01*
X693900Y597800D01*
G01X706506Y597299D02*
X709456D01*
X711256Y595499D01*
G01X699899Y607558D02*
Y602970D01*
G01D02*
X706177D01*
X706506Y603299D01*
G01X769812Y53660D02*
X774852Y58700D01*
X801236D01*
X802786Y57150D01*
G01X818785Y50692D02*
X759749D01*
X756431Y54010D01*
G01X764900Y210250D02*
X764160D01*
X762205Y212205D01*
G01X796829Y230575D02*
X796301Y231103D01*
X793701D01*
G01X762205Y212205D02*
X761150Y211150D01*
X759000D01*
G01X793701Y237402D02*
X794706D01*
X797099Y239795D01*
G01X790360Y242950D02*
X792913D01*
X793672Y243709D01*
G01X768479Y212214D02*
X767786D01*
X766250Y213750D01*
X764900D01*
G01D02*
Y216100D01*
X762205Y218795D01*
Y221654D01*
G01X784969Y218074D02*
Y218961D01*
X784252Y219678D01*
Y221654D01*
G01X777450Y218100D02*
Y221151D01*
X777953Y221654D01*
G01X777450Y214700D02*
Y218100D01*
G01X790850Y224400D02*
Y221953D01*
X790551Y221654D01*
G01X792269Y218044D02*
Y218774D01*
X790551Y220492D01*
Y221654D01*
G01X738350Y218800D02*
Y219601D01*
X739408Y220659D01*
Y220904D01*
X740158Y221654D01*
G01X759000Y218350D02*
Y214650D01*
G01X745850Y218800D02*
Y221047D01*
X746457Y221654D01*
G01X781127Y246863D02*
Y248067D01*
X782940Y249880D01*
G01X799200Y218100D02*
X802630D01*
G01X797099Y243295D02*
X796821Y243573D01*
Y246859D01*
G01D02*
X800791D01*
X800850Y246800D01*
G01X793701Y227954D02*
Y225609D01*
X796850Y222460D01*
Y221654D01*
G01X795719Y218074D02*
Y220277D01*
X796101Y220659D01*
Y220905D01*
X796850Y221654D01*
G01X799200Y218100D02*
X795745D01*
X795719Y218074D01*
G01X790360Y239450D02*
X792354D01*
X792706Y239802D01*
X792914D01*
X793672Y240560D01*
G01X790700Y227900D02*
X793647D01*
X793701Y227954D01*
G01X790700Y231350D02*
Y227900D01*
G01X796829Y234075D02*
X793880D01*
X793701Y234254D01*
G01X790700Y234770D02*
X793185D01*
X793701Y234254D01*
G01X749718Y294464D02*
Y291057D01*
X749605Y290944D01*
G01X737007D02*
Y291576D01*
X738718Y293287D01*
Y294464D01*
G01X746218D02*
Y291182D01*
X746456Y290944D01*
G01X740157D02*
Y291190D01*
X742218Y293251D01*
Y294464D01*
G01X740110Y287810D02*
Y290897D01*
X740157Y290944D01*
G01X759900Y492600D02*
X755500D01*
G01X745700Y498250D02*
Y495384D01*
X744600Y494284D01*
Y491534D01*
G01X818785Y50692D02*
X837792D01*
X841300Y54200D01*
G01X804350Y246800D02*
X808102D01*
X808923Y245979D01*
G01X815678Y253664D02*
Y250865D01*
X816079Y250464D01*
G01X813491Y206953D02*
X814262Y207724D01*
G01D02*
Y218950D01*
G01X824750Y240200D02*
Y244200D01*
G01D02*
X826900D01*
X828000Y243100D01*
G01X824718Y235964D02*
X824750Y235996D01*
Y240200D01*
G01X823550Y248200D02*
X824750Y247000D01*
Y244200D01*
G01X828800Y239350D02*
X825600D01*
X824750Y240200D01*
G01X802630Y218100D02*
X802650Y218080D01*
G01X802100Y222450D02*
Y218630D01*
X802630Y218100D01*
G01X806100Y222450D02*
X810100D01*
G01X802100D02*
X806100D01*
G01X818100D02*
X814100D01*
G01D02*
X810100D01*
G01X806210Y218090D02*
Y222340D01*
X806100Y222450D01*
G01X824718Y235964D02*
Y234682D01*
X826000Y233400D01*
G01X814450Y310400D02*
Y306950D01*
G01Y314600D02*
X814300D01*
X811600Y317300D01*
G01X843200Y481500D02*
X848600D01*
X849050Y481050D01*
G01X876569Y-65072D02*
Y-145072D01*
G01X1046569Y-65072D02*
Y-145072D01*
G01X1244069Y-65072D02*
Y-145072D01*
G01X1272069Y-49072D02*
G02I-12000J0D01*
G01X1266919D02*
G02I-6850J0D01*
G01X1276069D02*
X1244069D01*
G01X1260069Y-65072D02*
Y-33072D01*
X77780Y61790D03*
X73760Y67930D03*
X56960Y58900D03*
X54050Y63260D03*
X43510Y57810D03*
X29890Y54070D03*
X49460Y63690D03*
X68730Y67930D03*
X38590Y55260D03*
X30270Y48330D03*
X31100Y458733D03*
X26576Y457406D03*
X34132Y521245D03*
X34175Y526969D03*
X64277Y502177D03*
X75399Y502179D03*
X69904Y502077D03*
X41250Y494600D03*
X53524Y521269D03*
Y526995D03*
X75405Y521695D03*
X69778D03*
X64151D03*
X49600Y496050D03*
X55300Y495600D03*
X62276Y550493D03*
X28800Y549474D03*
X29158Y543855D03*
X29058Y538228D03*
X28782Y555119D03*
X29165Y532612D03*
X33697Y560866D03*
X37660Y566400D03*
X42597Y571789D03*
X71002Y577013D03*
X67853Y573865D03*
X75197Y572437D03*
X64701Y570716D03*
Y564416D03*
X67853Y558117D03*
X61100Y546700D03*
X64400Y539000D03*
X67852Y586463D03*
Y583313D03*
X74151Y545516D03*
X74498Y551757D03*
X71002Y539219D03*
X74076Y535966D03*
X75508Y542198D03*
X71002Y542368D03*
X67852Y539219D03*
X71002Y545518D03*
Y558117D03*
X74152Y567565D03*
X71002D03*
Y564396D03*
X74152Y580163D03*
Y577013D03*
X71002Y561266D03*
X67853Y564416D03*
X75066Y563235D03*
X71002Y554967D03*
X67853D03*
X78276Y545566D03*
X67853Y542368D03*
X71002Y548668D03*
X52408Y543876D03*
X64701Y542366D03*
X52603Y549526D03*
X52485Y555153D03*
X53300Y560879D03*
X67853Y570715D03*
X74152Y583312D03*
X64703Y586463D03*
X63456Y555041D03*
X64701Y567566D03*
Y561266D03*
X67853D03*
Y577015D03*
X53524Y532622D03*
X52613Y538242D03*
X53302Y567317D03*
X59200Y582200D03*
X64884Y650984D03*
X38550Y617950D03*
X50700Y664000D03*
X50800Y667900D03*
X40309Y660700D03*
X71850Y698900D03*
X47150Y665500D03*
X76100Y697100D03*
X97600Y54810D03*
X84610Y64470D03*
X98770Y60860D03*
X89070Y62600D03*
X114390Y453185D03*
X102250Y455000D03*
X108300Y435900D03*
X118108Y453159D03*
X121826Y453156D03*
X128968Y452741D03*
X125353Y452385D03*
X132109Y451199D03*
X136021Y451394D03*
X127812Y445066D03*
X107100Y497300D03*
X97926Y502300D03*
X86699D03*
X81094Y502166D03*
X138900Y525999D03*
X135012Y510200D03*
X119400Y511500D03*
X132100Y493000D03*
X133152Y484074D03*
X105350Y511850D03*
X114070Y481948D03*
X117200Y495200D03*
X105920Y477098D03*
X141980Y508590D03*
X97637Y492891D03*
X118900Y522000D03*
X138000Y485900D03*
X116500Y477000D03*
X144500Y489500D03*
X92286Y521695D03*
X81032D03*
X86659D03*
X97913D03*
X114500Y490000D03*
X137050Y476346D03*
X132774Y497000D03*
X89899Y558115D03*
X86750Y573864D03*
X89899D03*
X86750Y567565D03*
X89899Y564415D03*
X106272Y547370D03*
X94473Y547093D03*
X89901Y587466D03*
X93048Y577014D03*
X108371Y577258D03*
X136990Y535235D03*
X86750Y542368D03*
X126337Y554085D03*
X130311Y546700D03*
X81276Y548766D03*
X119605Y548705D03*
X86750Y539218D03*
X83600Y545518D03*
X89899D03*
X127300Y543200D03*
X89899Y539218D03*
X117200Y546300D03*
X83600Y539219D03*
X86750Y545518D03*
X122600Y557480D03*
X86750Y554965D03*
X130607Y569636D03*
X86750Y558115D03*
X126347Y569556D03*
X83600Y551817D03*
X117400Y567650D03*
X83600Y573865D03*
X86750Y586463D03*
Y583313D03*
X83601Y580164D03*
X89899Y577014D03*
X86750D03*
X83600Y564415D03*
X86750D03*
X83600Y561265D03*
X96570Y581730D03*
X86750Y551815D03*
X123300Y530300D03*
X133800Y528500D03*
X123200Y534600D03*
X143500Y529000D03*
X93744Y542019D03*
X133554Y537374D03*
X93051Y587466D03*
X83600Y567565D03*
X93049Y573864D03*
X89899Y567565D03*
X93048Y580164D03*
X89899Y561265D03*
X86750D03*
X94720Y557158D03*
X92600Y535623D03*
X96371Y534124D03*
X101400Y606300D03*
X97800D03*
X137210Y622030D03*
X134030Y620760D03*
X130630Y620900D03*
X101500Y597000D03*
X85500Y628500D03*
X122750Y616950D03*
X122000Y628700D03*
X144800Y657900D03*
X136100Y656300D03*
X125100Y656700D03*
X123370Y606700D03*
X119600D03*
X118500Y638100D03*
X140700Y657700D03*
X130800Y656100D03*
X127401Y606930D03*
X93053Y606734D03*
X142447Y611714D03*
X119000Y633200D03*
X120500Y651800D03*
X134650Y612900D03*
X144750Y606350D03*
X98200Y616900D03*
X129800Y630700D03*
X117050Y602000D03*
X116500Y621000D03*
X130800Y606700D03*
X138500Y637900D03*
X130500Y638600D03*
X134700D03*
X111300Y705500D03*
X107100Y679600D03*
X106879Y707245D03*
X125376Y701124D03*
X106355Y710745D03*
X106635Y701465D03*
X87683Y698924D03*
X84600Y688000D03*
X119849Y709715D03*
X146301Y460200D03*
X186602Y459767D03*
X197085Y459899D03*
X190278Y459865D03*
X193686Y459799D03*
X172200Y460100D03*
X157496Y461248D03*
X166600Y509800D03*
X166700Y499800D03*
X146263Y468562D03*
X203307Y506400D03*
X179000Y499800D03*
X203500Y513500D03*
X186735Y463748D03*
X207500Y503000D03*
X191418Y509981D03*
X170870Y492270D03*
X158000Y480700D03*
X146143Y481057D03*
X175100Y477000D03*
X208370Y491570D03*
X183100Y499800D03*
X170838Y481762D03*
X146300Y502600D03*
X146112Y509412D03*
X158100Y493000D03*
X158400Y513600D03*
X155001Y513707D03*
X182874Y513591D03*
X178869Y513593D03*
X174900Y499800D03*
X166600Y513600D03*
X170700D03*
X172370Y463798D03*
X187000Y468000D03*
X146293Y464338D03*
X146193Y476938D03*
X146293Y472738D03*
X186600Y477700D03*
X187000Y499500D03*
X146500Y492500D03*
X145400Y524046D03*
X176100Y473200D03*
X174700Y513900D03*
X182300Y509600D03*
X184780Y526990D03*
X187167Y513167D03*
X191100Y513367D03*
X154500Y487000D03*
X178869Y509793D03*
X209800Y478500D03*
X158290Y502380D03*
X205516Y467968D03*
X170700Y509800D03*
X170900Y500000D03*
X209256Y467946D03*
X172100Y467300D03*
X176800Y492200D03*
X175805Y524073D03*
X206180Y509524D03*
X191100Y526000D03*
X195149Y513751D03*
X150500Y493000D03*
X190950Y482100D03*
X200100Y491700D03*
X146216Y486045D03*
X196243Y486782D03*
X159480Y506590D03*
X155540Y506510D03*
X195300Y498900D03*
X150162Y525937D03*
X148527Y519491D03*
X191725Y523074D03*
X195300Y529400D03*
X148409Y575672D03*
X144876Y590854D03*
X148409Y579353D03*
X144876Y587173D03*
X175100Y529100D03*
X203610Y529397D03*
X168390Y532060D03*
X184830Y529960D03*
X149419Y535654D03*
X191200Y529400D03*
X199400D03*
X208000Y529300D03*
X149242Y531080D03*
X152584Y532922D03*
X152415Y540014D03*
X171020Y611020D03*
X200610Y639611D03*
X207900Y645600D03*
X169000Y640300D03*
X184967Y643983D03*
X200560Y635100D03*
X170940Y614400D03*
X191110Y611050D03*
X191370Y608190D03*
X208700Y625149D03*
X200879Y614739D03*
X145900Y641300D03*
X164800Y640200D03*
X173000Y640400D03*
X193610Y640040D03*
X189500Y639700D03*
X178140Y630330D03*
X196249Y630091D03*
X199400Y628646D03*
X163200Y610070D03*
X160420Y610170D03*
X184050Y629500D03*
X181176Y627600D03*
X209093Y615849D03*
X166690Y615060D03*
X166600Y617850D03*
X195900Y649350D03*
X203400Y649600D03*
X180700Y640460D03*
X204800Y617440D03*
X204642Y621140D03*
X177300Y626800D03*
X152700Y640800D03*
X161000Y634300D03*
X157200Y634200D03*
X196855Y698355D03*
X151130Y703440D03*
X148249Y695765D03*
X191766Y679920D03*
X202800Y660900D03*
X189000Y659900D03*
X206700Y695400D03*
X162100Y711215D03*
X151949Y691715D03*
X175233Y704382D03*
X163349Y702715D03*
X163260Y706988D03*
X169070Y696220D03*
X159519Y694455D03*
X193500Y663000D03*
X200400Y694700D03*
X196900Y661350D03*
X206300Y661100D03*
X181300Y679100D03*
X185100Y705600D03*
X184800Y709300D03*
X190200Y671000D03*
X187500Y673100D03*
X272000Y461800D03*
X268350Y461950D03*
X275100Y460300D03*
X259000Y453900D03*
X251700Y443600D03*
X268900Y445150D03*
X244700Y451200D03*
X236100Y445100D03*
X239300Y443800D03*
X243000D03*
X247900Y445300D03*
X260600Y442600D03*
X250500Y451300D03*
X224500Y445600D03*
X254900Y453900D03*
X232200Y445600D03*
X275500Y466200D03*
X211700Y513500D03*
X220100Y513400D03*
X211196Y487762D03*
X222600Y503500D03*
X246000Y516670D03*
X275700Y490300D03*
X244900Y527300D03*
X228150Y525750D03*
X275400Y470300D03*
X213100Y476300D03*
X261200Y525400D03*
X242500Y523500D03*
X213100Y472900D03*
X275200Y474500D03*
X258100Y516400D03*
X227500Y512200D03*
X265148Y524595D03*
X249050Y527150D03*
X258381Y509498D03*
X225914Y523051D03*
X231800Y512100D03*
X223600Y512400D03*
X213359Y480489D03*
X238400Y511300D03*
X265274Y509512D03*
X267800Y479900D03*
X222500Y536161D03*
X211500Y529400D03*
X230900Y581600D03*
X229800Y593200D03*
X247400Y589600D03*
X252593Y547650D03*
X261900Y591300D03*
X247100Y582400D03*
X246611Y551511D03*
X246484Y537139D03*
X269900Y567619D03*
X245743Y546963D03*
X270021Y549394D03*
X257000Y548400D03*
X263216Y554697D03*
X254530Y564300D03*
X251446Y553754D03*
X254500Y579500D03*
X273500Y567400D03*
X254300Y586500D03*
X273400Y590902D03*
X231434Y562844D03*
X234300Y582300D03*
X231200Y576800D03*
X231000Y571900D03*
X257300Y537500D03*
X214900Y529400D03*
X234943Y565199D03*
X254600Y567700D03*
X260731Y561264D03*
X260741Y542700D03*
X264333Y528926D03*
X258528Y555161D03*
X259100Y567706D03*
X257000Y571700D03*
X223900Y531200D03*
X228100Y545500D03*
X228800Y542100D03*
X228313Y552169D03*
X262000Y586900D03*
X257851Y580080D03*
X270145Y557526D03*
X261308Y583388D03*
X237100Y590000D03*
X257700Y586400D03*
X261500Y576400D03*
X261600Y580000D03*
X257891Y563786D03*
X257600Y576500D03*
X233607Y557671D03*
X254500Y575070D03*
X261100Y571600D03*
X234800Y572000D03*
X232400Y533200D03*
X248900Y545700D03*
X267957Y537304D03*
X274623Y578896D03*
X271357Y537253D03*
X233036Y550942D03*
X213800Y631200D03*
X212308Y605949D03*
X229796Y610104D03*
X270000Y602400D03*
X255228Y631071D03*
X255648Y626127D03*
X245300Y635700D03*
X254199Y603443D03*
X254600Y597100D03*
X229137Y634881D03*
X266857Y634343D03*
X256001Y612347D03*
X258869Y603050D03*
X266571Y608619D03*
X275470Y608480D03*
X270400Y622870D03*
X264040Y648370D03*
X219200Y647200D03*
X221900Y630800D03*
X218800Y635600D03*
X230900Y649100D03*
X211706Y645349D03*
X247725Y656375D03*
X246500Y601500D03*
X234000Y629576D03*
X218200Y651400D03*
X248450Y609900D03*
X266847Y626253D03*
X229063Y638560D03*
X216600Y658400D03*
X274800Y635000D03*
X222950Y647900D03*
X255570Y616631D03*
X258962Y616384D03*
X236000Y647400D03*
X225900Y630700D03*
X231500Y659100D03*
X228149Y600094D03*
X242710Y604620D03*
X226471Y649129D03*
X243322Y597509D03*
X251314Y598106D03*
X251338Y601506D03*
X258550Y606527D03*
Y610096D03*
X215606Y645806D03*
X229500Y631500D03*
X212900Y619201D03*
X273714Y629870D03*
X266571Y630071D03*
X245100Y647200D03*
X272200Y648550D03*
X221238Y620524D03*
X234205Y598743D03*
X233258Y595693D03*
X232130Y612950D03*
X251900Y609600D03*
X259777Y638873D03*
X242000Y656400D03*
X255733Y622329D03*
X253196Y706062D03*
X261248Y700086D03*
X272050Y711810D03*
X267880Y704920D03*
X262634Y711233D03*
X266400Y675349D03*
X265000Y662574D03*
X247825Y670375D03*
X235100Y679921D03*
X221575Y695400D03*
X242000Y693400D03*
X255050Y675750D03*
X254800Y689400D03*
X269200Y699600D03*
X258423Y711343D03*
X268520Y719420D03*
X270900Y667200D03*
X237509Y674915D03*
X266200Y679400D03*
X268384Y662909D03*
X263700Y723500D03*
X264700Y700000D03*
X214270Y695095D03*
X275300Y668749D03*
X217638Y695562D03*
X235000Y692900D03*
X262323Y716917D03*
X255200Y680950D03*
X239400Y677900D03*
X266300Y692574D03*
X254648Y745463D03*
X311715Y20397D03*
X310353Y62159D03*
X326553Y34687D03*
X340297Y117548D03*
X341484Y110328D03*
X339232Y113960D03*
X338743Y122894D03*
X305700Y197600D03*
X295841Y176793D03*
X323582Y179064D03*
X299107Y177740D03*
X295462Y173414D03*
X304231Y265048D03*
Y261048D03*
X322426Y223731D03*
Y227531D03*
X321197Y254433D03*
X322426Y231331D03*
X321782Y215974D03*
X306446Y247874D03*
X305382Y227474D03*
X305498Y213824D03*
X305703Y202165D03*
X306407Y206057D03*
X335000Y226992D03*
X305782Y230874D03*
X335082Y231574D03*
X322301Y220009D03*
X305782Y217274D03*
X305682Y224074D03*
X305782Y220674D03*
X305454Y244461D03*
X334998Y255520D03*
X305373Y251101D03*
X334998Y259033D03*
X306412Y254339D03*
X335060Y262516D03*
X305882Y234274D03*
X305772Y237673D03*
X321700Y246000D03*
X321600Y250000D03*
X305781Y241076D03*
X334582Y291284D03*
Y287284D03*
Y283784D03*
Y279784D03*
X307567Y331592D03*
Y328092D03*
Y324092D03*
X304267Y322892D03*
Y318892D03*
Y315392D03*
Y311392D03*
X307567Y310292D03*
Y306292D03*
Y302792D03*
Y298792D03*
X304267Y297692D03*
Y293692D03*
Y290192D03*
Y286192D03*
X334582Y330271D03*
X328182Y329174D03*
Y325174D03*
Y321674D03*
Y317674D03*
X334582Y316574D03*
Y312574D03*
Y309074D03*
Y305074D03*
X328182Y303977D03*
Y299977D03*
Y296477D03*
Y292477D03*
X307567Y285092D03*
Y281092D03*
Y277592D03*
Y273592D03*
X304231Y272548D03*
Y268548D03*
X321281Y266486D03*
X321432Y279090D03*
X321882Y291874D03*
Y304374D03*
X321432Y316885D03*
Y329484D03*
X328913Y274414D03*
X334017Y272000D03*
X337808Y288709D03*
X304267Y373292D03*
Y369292D03*
Y365792D03*
Y361792D03*
X307567Y360692D03*
Y356692D03*
Y353192D03*
Y349192D03*
X304267Y348092D03*
Y344092D03*
Y340592D03*
Y336592D03*
X307567Y335592D03*
X328182Y379518D03*
Y375518D03*
Y372018D03*
Y368018D03*
X334582Y366974D03*
Y362974D03*
Y359474D03*
Y355474D03*
Y341771D03*
Y337771D03*
Y334271D03*
X328182Y354371D03*
Y350371D03*
Y346871D03*
Y342871D03*
X321432Y342082D03*
Y354681D03*
X321202Y376887D03*
X321432Y367279D03*
X335982Y390874D03*
X334000Y382700D03*
X303680Y380972D03*
X316900Y384100D03*
X319679Y387121D03*
X314000Y390500D03*
X335800Y379800D03*
X338800Y435100D03*
X281200Y453500D03*
X333850Y458400D03*
X286700Y457500D03*
X323759Y435145D03*
X327159Y435201D03*
X276634Y498311D03*
X307364Y505750D03*
X321976D03*
X329035Y519325D03*
X293793Y521556D03*
X321208Y519411D03*
X325136Y519316D03*
X333922Y527323D03*
X340961Y511600D03*
X298335Y521458D03*
X304800Y512800D03*
X308687Y519193D03*
X302307Y505799D03*
X298907Y505851D03*
X336600Y504500D03*
X336800Y499967D03*
X325400Y505800D03*
X282403Y474500D03*
X282400Y470200D03*
X328200Y511600D03*
X331200Y508900D03*
X299448Y511300D03*
X277603Y479948D03*
X332821Y515415D03*
X280939Y504705D03*
X314400Y505750D03*
X334650Y508900D03*
X300476Y546907D03*
X285800Y549394D03*
X303100Y587000D03*
X292850Y586100D03*
X293271Y557248D03*
X327110Y583660D03*
X316680Y583527D03*
X337899Y587874D03*
X285982Y542502D03*
X310350Y538293D03*
X330860Y551744D03*
X325447Y536109D03*
X325774Y547428D03*
X331700Y587896D03*
X303520Y550085D03*
X296835Y591015D03*
X280646Y557150D03*
X303500Y582200D03*
X333847Y531105D03*
X286195Y530579D03*
X291800Y576708D03*
X337550Y534619D03*
X295824Y578108D03*
X323659Y557310D03*
X334900Y586100D03*
X333512Y553888D03*
X281610Y590260D03*
X324200Y565300D03*
X281490Y586862D03*
X337300Y583000D03*
X336367Y549943D03*
X294107Y560762D03*
X330729Y557268D03*
X327059Y557247D03*
X288309Y566467D03*
X291000Y570810D03*
X277048Y590470D03*
X319529Y562413D03*
X319252Y566509D03*
X285912Y538750D03*
X318736Y549697D03*
X280100Y532100D03*
X322889Y529380D03*
X322843Y533254D03*
X279664Y535473D03*
X328771Y549035D03*
X332808Y547575D03*
X332834Y543993D03*
X341316Y545000D03*
X282000Y583500D03*
X298514Y550184D03*
X293087Y530571D03*
X325687Y551368D03*
X319430Y557486D03*
X276839Y582309D03*
X277441Y539882D03*
X310292Y532128D03*
X339081Y628173D03*
X290300Y636900D03*
X290500Y640600D03*
X331655Y603405D03*
X339822Y609785D03*
X339847Y620281D03*
X305470Y623734D03*
X278546Y633450D03*
X281900Y640900D03*
X317600Y603300D03*
X339266Y658409D03*
X278443Y648857D03*
X284495Y613130D03*
X286700Y622190D03*
X340100Y631417D03*
X339751Y616882D03*
Y613185D03*
X335036Y603039D03*
X338733D03*
X294500Y630600D03*
X298100Y630650D03*
X334700Y644500D03*
X302459Y599531D03*
X306100Y599500D03*
X306231Y602898D03*
X302180Y603084D03*
X335100Y650600D03*
X338100Y635800D03*
X331718Y655832D03*
X329100Y650700D03*
X317689Y599833D03*
X287200Y632600D03*
X290900Y630900D03*
X278769Y700697D03*
X318400Y678400D03*
X325900Y678500D03*
X281400Y708200D03*
X281500Y712200D03*
X279400Y686400D03*
X294804Y695204D03*
X296800Y665081D03*
X311600Y670354D03*
X319600Y670450D03*
X293300Y679700D03*
X321800Y678500D03*
X281000Y678000D03*
X304400Y665100D03*
X316465Y716063D03*
X340500Y711750D03*
X335750Y664700D03*
X288700Y667900D03*
X340100Y718200D03*
X327162Y696776D03*
X282300Y700100D03*
X276800Y697925D03*
X338669Y691580D03*
X339804Y679030D03*
X340403Y699400D03*
X340300Y703100D03*
X336200Y677000D03*
X289700Y678830D03*
X280646Y717540D03*
X276100Y677700D03*
X300100Y670300D03*
X304700Y668500D03*
X298570Y743670D03*
X306470Y743570D03*
X278553Y740020D03*
X291700Y737000D03*
X287620Y737300D03*
X290000Y727000D03*
X313873Y735907D03*
X314100Y739300D03*
X380500Y33500D03*
Y30000D03*
X384000D03*
X381173Y49058D03*
X381156Y54116D03*
X375200Y63400D03*
X370870Y45605D03*
X368059Y57759D03*
X354798Y22452D03*
X375300Y72150D03*
X374844Y87900D03*
X375000Y107300D03*
X393206Y77614D03*
X374844Y76700D03*
X362000Y124000D03*
X386759Y79693D03*
X390456D03*
X342539Y120370D03*
X369253Y88733D03*
X367287Y77118D03*
X381269Y94981D03*
X384666Y93741D03*
X349206Y129948D03*
X390964Y87226D03*
X388700Y89800D03*
X349072Y193574D03*
X400212Y154732D03*
X400351Y165605D03*
X349072Y189774D03*
X371775Y200577D03*
X348082Y186224D03*
X370149Y167337D03*
X370882Y163688D03*
X387202Y164664D03*
X387393Y160859D03*
X404727Y162141D03*
X392102Y175384D03*
X400205Y158209D03*
Y161906D03*
X392458Y171676D03*
X400430Y147190D03*
X362197Y222068D03*
X362722Y237674D03*
X361792Y243154D03*
X372888Y208022D03*
X359882Y203458D03*
X347482Y254774D03*
X341882Y251064D03*
X342885Y276301D03*
X342958Y279701D03*
X383170Y329807D03*
X345582Y380874D03*
X344732Y393882D03*
Y390274D03*
X383285Y347114D03*
X383327Y343379D03*
X396561Y351418D03*
X346600Y375000D03*
X344732Y386874D03*
X365100Y348300D03*
X372491Y378025D03*
X365200Y344400D03*
X378492Y378175D03*
X383030Y352442D03*
X367358Y372531D03*
X367471Y369120D03*
X360100Y453500D03*
X342700Y435200D03*
X350491Y453809D03*
X372000Y452100D03*
X369900Y458700D03*
X387450Y454558D03*
X387396Y458126D03*
X384395Y449114D03*
X374700Y460300D03*
X350400Y459000D03*
X381106Y441241D03*
X350400Y462400D03*
X374650Y456771D03*
X346500Y435200D03*
X364500Y453700D03*
X367400Y461200D03*
X355400Y453800D03*
X357900Y450800D03*
X369000Y512700D03*
X345497Y527644D03*
X355300Y510100D03*
X353300Y521400D03*
X344700Y509000D03*
X368721Y525271D03*
X371900Y481548D03*
X365800Y498300D03*
X357450Y491450D03*
X364500Y525260D03*
X369300Y508700D03*
X344400Y505400D03*
X344500Y500300D03*
X363500Y464700D03*
X372000Y477710D03*
X355300Y502700D03*
X357700Y499000D03*
X400080Y500854D03*
X384849Y525499D03*
Y521681D03*
X355300Y506100D03*
Y513500D03*
X386367Y474700D03*
X400080Y519500D03*
Y491107D03*
Y523903D03*
Y528243D03*
X389349Y480100D03*
X381986Y515631D03*
X374751Y485636D03*
X374715Y498722D03*
X366950Y464700D03*
X341500Y520400D03*
X373699Y521160D03*
X359100Y503200D03*
X374800Y516912D03*
X387450Y467000D03*
X389288Y483500D03*
X358800Y478000D03*
X370900Y464700D03*
X349088Y500296D03*
X373500Y540305D03*
X393912Y568499D03*
X351600Y540600D03*
X348314Y585614D03*
X385600Y529107D03*
X372600Y576207D03*
X374292Y580300D03*
X355012Y582324D03*
X363008Y547309D03*
X371227Y566830D03*
X384950Y560496D03*
X383000Y577000D03*
X386305Y581647D03*
X362700Y551200D03*
X361279Y581647D03*
X362100Y574700D03*
X349000Y581360D03*
X379050Y539931D03*
X341740Y535800D03*
X352279Y580294D03*
X346303Y591947D03*
X386723Y544565D03*
X342440Y571770D03*
X361900Y570800D03*
X369500Y542900D03*
X388641Y549747D03*
X400093Y536351D03*
X399726Y562327D03*
X399946Y558677D03*
X345259Y557566D03*
X391993Y582154D03*
X362300Y555200D03*
X343840Y566440D03*
X348300Y565400D03*
X364900Y585171D03*
X372939Y559838D03*
X346590Y572090D03*
X350278Y572306D03*
X366270Y563400D03*
X373222Y535938D03*
X370247Y546218D03*
X370223Y549965D03*
X384950Y551876D03*
Y555276D03*
X383056Y563675D03*
X400060Y554743D03*
X393912Y571899D03*
X393910Y575305D03*
X341493Y541250D03*
X393912Y578705D03*
X348600Y643500D03*
X344564Y628104D03*
X379400Y641800D03*
X385163Y641354D03*
X342133Y603008D03*
X391150Y613429D03*
X350500Y647600D03*
X355000Y652160D03*
X374200Y645871D03*
X370200Y636400D03*
X359036Y635900D03*
X359258Y596820D03*
X383300Y600600D03*
X384410Y633530D03*
X348000Y612661D03*
X352720Y600970D03*
X367133Y596067D03*
X382380Y612277D03*
X352400Y626102D03*
X372408Y629626D03*
X364014Y593996D03*
X343797Y631417D03*
X381967Y616123D03*
X361227Y630300D03*
X377700Y595000D03*
X383199Y623168D03*
X382438Y608755D03*
X384158Y638105D03*
X380443D03*
X400064Y652598D03*
X384300Y619925D03*
X354102Y660666D03*
X392720Y697500D03*
X376342Y711260D03*
X358296Y672460D03*
X346465Y703185D03*
X364200Y713100D03*
X369600Y693400D03*
X351100Y712100D03*
X384220Y700618D03*
X367600Y696800D03*
X396166Y692630D03*
X343200Y667600D03*
X389999Y664697D03*
X367700Y685450D03*
X343338Y679236D03*
X399999Y673422D03*
X396419Y679708D03*
X398983Y706749D03*
X382308Y665022D03*
X396419Y686586D03*
X372350Y698400D03*
X399093Y703350D03*
X380300Y703000D03*
X399154Y699950D03*
X341900Y690350D03*
X346600Y714500D03*
X346000Y684300D03*
X383800Y688400D03*
X392800Y677600D03*
X341934Y662794D03*
X378595Y664960D03*
X388626Y715509D03*
X392500Y692500D03*
X355298Y711750D03*
X396419Y683186D03*
X459950Y58000D03*
X469058Y49156D03*
X439200Y22100D03*
X439549Y26339D03*
X439554Y30429D03*
X439302Y34040D03*
X458972Y49634D03*
X462625Y49881D03*
X467300Y20000D03*
X450454Y38147D03*
X448520Y49979D03*
X430800Y22200D03*
X433600Y19900D03*
X428001Y25269D03*
X433400Y63373D03*
X438600Y91033D03*
X419662Y71426D03*
X423340Y71621D03*
X469901Y94047D03*
X415211Y71263D03*
X461736Y111300D03*
X442800Y90934D03*
X496700Y32100D03*
X482693Y42200D03*
X478500Y19775D03*
X490050Y45900D03*
X506970Y18693D03*
X502830D03*
X477400Y69300D03*
X512806Y49494D03*
X473151Y50052D03*
X521200Y57600D03*
X496035Y46435D03*
X503814Y56676D03*
X515500Y57900D03*
X486568Y38006D03*
X486114Y41700D03*
X496430Y22890D03*
X491270Y18877D03*
X485674Y32924D03*
X524950Y16120D03*
X473172Y95508D03*
X479147Y102165D03*
X490100Y111300D03*
X486400Y74700D03*
X481800Y71200D03*
X513909Y85849D03*
X510408Y85779D03*
X559200Y36265D03*
X552540Y64530D03*
X599422Y51662D03*
X568430Y50010D03*
X596489Y14110D03*
X559600Y47600D03*
X575550Y42800D03*
X601311Y13521D03*
X569300Y66274D03*
X545200Y69000D03*
X596300Y66950D03*
X549550Y61900D03*
X597950Y58950D03*
X573600Y49750D03*
X577100Y78600D03*
X545300Y75600D03*
X568000Y70000D03*
X584550Y80750D03*
X559900Y88400D03*
X563268Y88872D03*
X540179Y111036D03*
X539346Y114333D03*
X578900Y82500D03*
X551500Y82400D03*
X599682Y103715D03*
X547100Y79900D03*
X578400Y74500D03*
X562160Y178600D03*
X582219Y386612D03*
X599998Y391270D03*
X598964Y354128D03*
X596077Y369579D03*
X602075Y339970D03*
X593064Y400910D03*
X593229Y397308D03*
X666535Y26149D03*
X665800Y7550D03*
X666400Y22200D03*
X638470Y164470D03*
X634910Y169360D03*
X644100Y199850D03*
X630000Y169600D03*
X629500Y187500D03*
X619980Y197550D03*
X634000Y187500D03*
X630800Y147600D03*
X634800Y147700D03*
X666700Y205600D03*
X629400Y217300D03*
X644100Y203350D03*
X634450Y252100D03*
X631550Y249850D03*
X625926Y247530D03*
X627200Y253550D03*
X625250Y264250D03*
X625550Y244150D03*
Y240750D03*
X645516Y225334D03*
X620750Y258050D03*
X642547Y226992D03*
X632958Y231000D03*
X633109Y234397D03*
X632900Y238000D03*
X628300Y230550D03*
X625700Y235750D03*
X640141Y259859D03*
X640400Y217600D03*
X636491Y217592D03*
X633092Y217496D03*
X659500Y205300D03*
X662900D03*
X645400Y264050D03*
X620160Y203500D03*
X648700Y292900D03*
X660700Y292200D03*
X634830Y292095D03*
X638453Y291949D03*
X633400Y274600D03*
X652850Y269600D03*
X642300Y276450D03*
X649000Y273500D03*
X652100Y279300D03*
X656700Y305607D03*
X664600Y306100D03*
X648700Y303600D03*
X652500Y305707D03*
X638603Y296320D03*
X642003Y296249D03*
X645403Y296229D03*
X631069Y292512D03*
X654670Y391494D03*
X616428Y379533D03*
X626772Y371336D03*
X612300Y344300D03*
X613480Y333710D03*
X629900Y339300D03*
X610300Y354800D03*
X654600Y367600D03*
X639318Y354003D03*
X643082Y353941D03*
X629239Y387969D03*
X620100Y384100D03*
X608600Y362600D03*
X659300Y373100D03*
X637000Y373856D03*
X632220Y389694D03*
X607800Y382362D03*
X607100Y351200D03*
X638360Y383805D03*
X642270Y383869D03*
X605400Y393400D03*
X618600Y364375D03*
X609240Y370337D03*
X616900Y343000D03*
X615150Y364200D03*
X640968Y370425D03*
X606626Y354723D03*
X637353Y379591D03*
X657900Y443200D03*
X655100Y436900D03*
X636963Y405999D03*
X632180Y397968D03*
X654300Y504100D03*
X613000Y463000D03*
X666216Y470684D03*
X632800Y561600D03*
X620160Y544793D03*
X610200Y555400D03*
X628160Y569095D03*
X619400Y570451D03*
X653600Y540300D03*
X635970Y557600D03*
X638660Y568043D03*
X616160Y542700D03*
X614000Y561250D03*
X606600Y551100D03*
X722150Y174300D03*
X727150Y184550D03*
X722150D03*
X711150Y174300D03*
X716650Y184550D03*
X711150D03*
X705650D03*
X677770Y196410D03*
X730550Y179050D03*
X732000Y185900D03*
X716650Y174400D03*
X674300Y198900D03*
X704579Y258164D03*
X721261Y240551D03*
X721260Y234252D03*
X730710Y256302D03*
X733858Y256299D03*
Y253149D03*
X730710Y253152D03*
X733859Y234253D03*
Y237403D03*
X730710D03*
Y234254D03*
X733858Y243700D03*
Y246849D03*
Y249999D03*
Y265747D03*
X730710Y240553D03*
Y243702D03*
Y246852D03*
Y250002D03*
Y265750D03*
X721295Y221651D03*
X718089Y243684D03*
X721260Y253150D03*
Y259449D03*
Y265748D03*
X721261Y246851D03*
X733859Y240552D03*
X727559Y259449D03*
Y265748D03*
Y253150D03*
Y240551D03*
X727560Y246851D03*
X727559Y221654D03*
Y234252D03*
X727594Y227950D03*
X696600Y241500D03*
X701500Y250564D03*
X691600Y207600D03*
X718121Y256326D03*
X718089Y246834D03*
X718098Y259423D03*
X718072Y265748D03*
X718089Y249984D03*
X718129Y253144D03*
X693800Y264300D03*
X725466Y200819D03*
X707923Y219765D03*
X708900Y214500D03*
X718111Y224802D03*
X706500Y212150D03*
X709615Y223228D03*
X718111Y231101D03*
X696300Y215750D03*
X702900Y212350D03*
X707679Y233664D03*
X718111Y227952D03*
X722322Y200935D03*
X704279Y226664D03*
X705529Y231064D03*
X705779Y236764D03*
X706079Y240664D03*
X710716Y235827D03*
X714945Y234230D03*
X726988Y204312D03*
X718123Y201101D03*
X710079Y203664D03*
X718895Y207125D03*
X705364Y205864D03*
X713168Y207689D03*
X718111Y221653D03*
X733859Y215355D03*
X718110Y234252D03*
X709679Y239164D03*
X727560Y215355D03*
X716116Y207469D03*
X718111Y237401D03*
X709079Y229564D03*
X703979Y219995D03*
X718111Y240550D03*
X711812Y243700D03*
X714961D03*
X730709Y215355D03*
X724410D03*
X732264Y204312D03*
X703320Y203900D03*
X733859Y212206D03*
X729800Y208400D03*
X730709Y221654D03*
X733858D03*
X724410D03*
Y234252D03*
Y240551D03*
Y246850D03*
Y253150D03*
Y227953D03*
Y265748D03*
Y259449D03*
X704579Y261964D03*
X682030Y253630D03*
X706100Y250000D03*
X690600Y230700D03*
X691243Y211743D03*
X692600Y201300D03*
X677800Y215900D03*
X724410Y281496D03*
X730710D03*
X733859D03*
Y275198D03*
X730710Y272048D03*
X733858Y268897D03*
X721820Y315750D03*
X730710Y268899D03*
X721260Y275196D03*
Y272047D03*
X733859Y278346D03*
X677300Y314900D03*
X681200D03*
X684400Y313400D03*
X688000Y313200D03*
X694675Y323900D03*
X730708Y290944D03*
X724409D03*
X727559Y272047D03*
Y278346D03*
X708100Y331410D03*
X718340Y315800D03*
X706796Y295829D03*
X726895Y309117D03*
X711799Y304234D03*
X713339Y306954D03*
X724063Y306305D03*
X698039Y285854D03*
X707834Y293060D03*
X707079Y286964D03*
X704079Y300964D03*
X719200Y307400D03*
X705579Y298464D03*
X695508Y288964D03*
X710679Y267894D03*
X721230Y284653D03*
X718099Y290964D03*
X710329Y285214D03*
X718117Y281465D03*
X718080Y284653D03*
X701708Y292364D03*
X706277Y279162D03*
X718072Y278346D03*
X708409Y276771D03*
X733892Y297246D03*
X730708Y297243D03*
X714619Y303884D03*
X692750Y293200D03*
X718109Y272034D03*
X694307Y283485D03*
X722468Y308964D03*
X727558Y297243D03*
X733859Y272048D03*
X690579Y299964D03*
X675555Y318736D03*
X672350Y317600D03*
X724409Y297243D03*
X700323Y283078D03*
X716300Y331340D03*
X733859Y284646D03*
X695300Y306700D03*
X718099Y287814D03*
X712410Y331320D03*
X702250Y329650D03*
X733857Y290944D03*
X727558D03*
X730300Y314900D03*
X724410Y272047D03*
Y278346D03*
Y284645D03*
X669950Y310950D03*
X681800Y287950D03*
X718137Y275186D03*
X702939Y281484D03*
X718109Y268934D03*
X714949Y287814D03*
X731400Y362700D03*
X727000Y353000D03*
X712417Y352800D03*
X718300Y362900D03*
X722500Y353000D03*
X718000D03*
X713500Y362900D03*
X729900Y393200D03*
X708300Y445800D03*
X709006Y410206D03*
X721504Y402321D03*
X699900Y453600D03*
X691813Y407210D03*
X691874Y410741D03*
X691873Y403800D03*
X690550Y453850D03*
X690300Y460200D03*
X720900Y412900D03*
X728874Y470860D03*
X725366Y470722D03*
X677275Y485625D03*
X683583Y485841D03*
X702824Y476476D03*
X682400Y463400D03*
X696800Y476400D03*
X689100Y507900D03*
X730600Y493100D03*
X716078Y492334D03*
X672500Y507100D03*
X696000Y508400D03*
X715391Y479109D03*
X703440Y548820D03*
X710459Y554134D03*
X719626Y590829D03*
X725000Y576100D03*
X714800Y567956D03*
X710000Y549100D03*
X710100Y545600D03*
X705176Y593429D03*
X717450Y551554D03*
X697200Y529200D03*
X705676Y562429D03*
X722300Y608200D03*
X708600Y608500D03*
X702515Y597064D03*
X693900Y597800D03*
X703800Y608400D03*
X712708Y603038D03*
X723369Y599835D03*
X722122Y611840D03*
X777550Y62350D03*
X795832Y66750D03*
X787360Y35650D03*
X776300Y47600D03*
X769812Y53660D03*
X756431Y54010D03*
X736803Y52087D03*
X779400Y54750D03*
X746500Y47200D03*
X780815Y47062D03*
X776600Y35250D03*
X762765Y42200D03*
X761900Y81700D03*
X772700Y113000D03*
X794650Y86050D03*
X769710Y125150D03*
X766110Y125270D03*
X793957Y113436D03*
X761950Y126450D03*
X773200Y97600D03*
X781250Y101750D03*
X779594Y126865D03*
X762000Y113000D03*
X763825Y89975D03*
X776500Y82700D03*
X750500Y118500D03*
X750600Y114200D03*
X769500Y91000D03*
X792600Y101300D03*
X772800Y107550D03*
X776850Y115050D03*
X749600Y199300D03*
X749400Y195600D03*
X753800Y181500D03*
X753400Y185400D03*
X741300Y185700D03*
X738160Y199480D03*
X749900Y185200D03*
X786343Y179959D03*
X745700Y185900D03*
X769100Y187800D03*
X786388Y183429D03*
X772810Y179901D03*
X772700Y183300D03*
X737000Y185900D03*
X765900Y191900D03*
X764900Y207200D03*
X768505Y243702D03*
X784277Y243713D03*
X784253Y227953D03*
Y231103D03*
X752756Y234253D03*
Y231103D03*
Y224804D03*
Y227954D03*
X749606Y231103D03*
Y234253D03*
Y227954D03*
Y224804D03*
X737008Y256299D03*
X740158D03*
Y253149D03*
X737008D03*
X771655Y237402D03*
X765353D03*
X737009Y237400D03*
X737008Y243700D03*
Y246849D03*
Y249999D03*
Y265747D03*
X740158Y246849D03*
Y265747D03*
X740122Y243700D03*
X740158Y249999D03*
X752756Y221654D03*
X737008D03*
X771654Y253150D03*
X777954Y237402D03*
Y227953D03*
Y231103D03*
X765355Y265749D03*
X771654Y259449D03*
Y265749D03*
X793701Y221654D03*
X781103Y227954D03*
X784277Y246863D03*
X784267Y259426D03*
X746457Y224804D03*
X755906D03*
X737009Y227953D03*
Y234253D03*
Y231103D03*
X774804Y221655D03*
Y224804D03*
Y227954D03*
X746457D03*
X755906D03*
X746457Y231103D03*
X755906D03*
X746457Y234253D03*
X755906D03*
X759056Y253150D03*
X765355Y234253D03*
X765354Y231102D03*
X765355Y227953D03*
X765354Y246850D03*
X784277Y253162D03*
X740132Y240562D03*
X759055Y221654D03*
X765355Y224804D03*
X771654Y215355D03*
Y209056D03*
Y212205D03*
X746457Y240552D03*
X752757D03*
X759056D03*
X746421Y253149D03*
X749455Y202200D03*
X765354Y221654D03*
X743307D03*
X762205Y215355D03*
X781103Y237402D03*
Y231103D03*
X787402Y221654D03*
X787401Y215354D03*
X746457Y246850D03*
X752720Y253149D03*
X752757Y246851D03*
X765355Y253150D03*
X759056Y246851D03*
X746433Y265761D03*
X746457Y259449D03*
X752757D03*
Y265749D03*
X765355Y259449D03*
X759056Y265749D03*
X759031Y259461D03*
X777976Y265761D03*
X784267Y256276D03*
X793701Y231103D03*
X793672Y243709D03*
X799991Y249972D03*
X799972Y262588D03*
X796822D03*
Y256289D03*
X790551Y259486D03*
X790538Y265723D03*
X793701Y237402D03*
X777976Y259461D03*
X781102Y221654D03*
X749606D03*
X762205Y212205D03*
X761600Y207300D03*
X787402Y240552D03*
Y243701D03*
X793700Y256262D03*
X752759Y218499D03*
X755909Y218514D03*
X790550Y253150D03*
X799972Y256309D03*
X781080Y265763D03*
X784258Y262618D03*
X777967Y262576D03*
X790523Y256289D03*
X800021Y243717D03*
X795593Y206063D03*
X777953Y256300D03*
X781300Y207800D03*
X774803Y265749D03*
X737009Y240552D03*
X746457Y215355D03*
X737029Y215337D03*
X743279Y215364D03*
X740158Y215355D03*
X743279Y212196D03*
X741294Y208274D03*
X743008Y206059D03*
X765355Y240552D03*
X743307Y246850D03*
X762217Y240526D03*
X755880Y240563D03*
X749580D03*
X755869Y253149D03*
X762167Y246850D03*
X755907Y246851D03*
X749569Y246850D03*
X762168Y253149D03*
X749608Y253150D03*
X743282Y253161D03*
X755868Y265748D03*
X755882Y259461D03*
X762218Y259425D03*
X749582Y259461D03*
X743282D03*
X762181Y265762D03*
X749582Y265761D03*
X743282D03*
X743281Y240562D03*
X768480Y265762D03*
X768518Y259425D03*
X768467Y253149D03*
Y246850D03*
X771653Y246887D03*
X762205Y221654D03*
X784252D03*
X777953D03*
X790551D03*
X740158D03*
X755906D03*
X746457D03*
X793701Y234254D03*
X781127Y246863D03*
X793672Y240560D03*
X796821Y246859D03*
X793701Y227954D03*
X796850Y221654D03*
X793674Y265758D03*
X793699Y262634D03*
X768504Y215355D03*
X763963Y331837D03*
X766437Y329363D03*
X769266Y326534D03*
X748737Y330263D03*
X751566Y327434D03*
X762229Y290933D03*
X752756Y278346D03*
X759073Y287810D03*
X774826Y268910D03*
X737009Y281496D03*
X740159Y278345D03*
Y281496D03*
X759031Y275209D03*
X765356Y272048D03*
Y275197D03*
Y278347D03*
X740158Y275197D03*
Y272046D03*
X737008D03*
Y268897D03*
X740158D03*
X746457Y272047D03*
Y275197D03*
X752757D03*
X752731Y272060D03*
X762181D03*
X759031D03*
X762206Y275197D03*
Y278347D03*
X737009Y275196D03*
X790551Y284646D03*
X781100Y287800D03*
X787419Y278354D03*
X737007Y290944D03*
X749579Y297254D03*
X787402Y297243D03*
X781102Y297244D03*
X771654Y297243D03*
X759058Y300414D03*
X768503Y287794D03*
X774802D03*
X787400Y287795D03*
X749607Y275197D03*
X774789Y275174D03*
X784221Y284652D03*
X777915Y281496D03*
X762189Y281514D03*
X768489Y281474D03*
X777953Y275198D03*
Y278347D03*
X784290Y272047D03*
X743306Y290944D03*
X749606Y278346D03*
X749593Y284670D03*
X799999Y290944D03*
Y284645D03*
Y278345D03*
X799974Y272058D03*
X793701Y300393D03*
X790519Y272053D03*
X790550Y287795D03*
X749605Y290944D03*
X762204Y287794D03*
X781064Y272047D03*
X784243Y278318D03*
X780300Y309300D03*
X740157Y297243D03*
X737008Y297244D03*
X740158Y284646D03*
X744881Y309000D03*
X743306Y297243D03*
X790526Y300406D03*
X765369Y281474D03*
X771669D03*
X781120Y284665D03*
X759070Y281514D03*
X749816Y303716D03*
X777790Y304778D03*
X769768Y304464D03*
X759208Y304284D03*
X784252Y268885D03*
X796839Y290934D03*
X787438Y275197D03*
X796832Y272064D03*
X796875Y304331D03*
X796862Y281522D03*
X784249Y281464D03*
X787426Y272060D03*
X790551Y278384D03*
X743308Y284646D03*
X746457D03*
X737009D03*
X744400Y322800D03*
X746456Y297243D03*
X765353Y287794D03*
X771653D03*
X777952D03*
X784251D03*
X762225Y297227D03*
X755898Y287804D03*
X743283Y272060D03*
X755882D03*
X749581D03*
X746456Y290944D03*
X740157D03*
X793700Y297243D03*
X796849D03*
X790545Y290959D03*
X793694D03*
X793703Y287797D03*
X796839Y287784D03*
X793675Y284637D03*
X793679Y281508D03*
X793675Y278357D03*
X796868Y278364D03*
X793737Y275196D03*
X793682Y272064D03*
X793683Y268879D03*
X796850Y268910D03*
X799534Y339466D03*
X760252Y353266D03*
X763081Y350437D03*
X765555Y347963D03*
X768384Y345134D03*
X761134Y334666D03*
X772352Y341266D03*
X775181Y338437D03*
X777655Y335963D03*
X780484Y333134D03*
X777434Y353566D03*
X780263Y350737D03*
X782737Y348263D03*
X785566Y345434D03*
X789334Y341766D03*
X792163Y338937D03*
X794637Y336463D03*
X797466Y333634D03*
X743434Y335566D03*
X746263Y332737D03*
X749534Y346566D03*
X752363Y343737D03*
X754837Y341263D03*
X757666Y338434D03*
X795026Y374556D03*
X799426Y374456D03*
X738465Y352935D03*
X790357Y377781D03*
X774700Y483600D03*
X794700Y505200D03*
X747125Y483924D03*
X743726Y483813D03*
X755500Y492600D03*
X768500Y480000D03*
X740253Y483893D03*
X797323Y512162D03*
X782000Y505600D03*
X771184Y514916D03*
X745700Y498250D03*
X742300Y498200D03*
X759000Y482900D03*
X759169Y497414D03*
X750600Y497400D03*
X759200Y508000D03*
X777600Y512200D03*
X781700Y510900D03*
X736600Y500000D03*
X780750Y496750D03*
X781050Y492550D03*
X757099Y530082D03*
X763809Y537191D03*
X782709Y537691D03*
X753099Y530282D03*
X795922Y531500D03*
X747200Y611900D03*
X826925Y57425D03*
X802786Y57150D03*
X841300Y54200D03*
X818785Y50692D03*
X803000Y117100D03*
X813349Y73142D03*
X809349Y73197D03*
X821962Y189277D03*
X801385Y183067D03*
X801340Y179597D03*
X831504Y199129D03*
X843419Y261781D03*
X840591Y264609D03*
X837619Y255281D03*
X834791Y258109D03*
X831609Y261291D03*
X828781Y264119D03*
X836955Y245662D03*
X834127Y248490D03*
X830945Y251672D03*
X828117Y254500D03*
X832148Y204444D03*
X816079Y250464D03*
X802227Y208424D03*
X802246Y205826D03*
X807468Y234464D03*
X808923Y245979D03*
X806968Y253464D03*
X804600Y210800D03*
X808400D03*
X816900Y231700D03*
X803160Y259454D03*
X803150Y256336D03*
X807177Y261023D03*
X814262Y218950D03*
X810277Y243190D03*
X810688Y238944D03*
X803129Y240535D03*
X803158Y237414D03*
X806862Y243302D03*
X806918Y237804D03*
X826000Y233400D03*
X828000Y243100D03*
X854419Y307581D03*
X851591Y310409D03*
X848409Y313591D03*
X845581Y316419D03*
X858919Y292081D03*
X856091Y294909D03*
X852909Y298091D03*
X850081Y300919D03*
X852919Y286081D03*
X850091Y288909D03*
X846909Y292091D03*
X844081Y294919D03*
X849419Y267581D03*
X846591Y270409D03*
X843409Y273591D03*
X840581Y276419D03*
X847419Y280581D03*
X844591Y283409D03*
X841409Y286591D03*
X838581Y289419D03*
X837409Y267791D03*
X834581Y270619D03*
X807666Y331334D03*
X822817Y331022D03*
X825646Y328193D03*
X803300Y303700D03*
X810300Y326450D03*
X823250Y319350D03*
X814450Y306950D03*
X810079Y271264D03*
X809968Y290464D03*
X808400Y300900D03*
X812164Y279674D03*
X811600Y317300D03*
X802363Y336637D03*
X804837Y334163D03*
X817514Y336325D03*
X820343Y333496D03*
X810946Y389734D03*
X811112Y393735D03*
X857581Y391433D03*
X817700Y385700D03*
X851100Y407500D03*
X861000Y410500D03*
X806400Y398700D03*
X810100Y404934D03*
X857000Y410600D03*
X850950Y489300D03*
X846000Y476100D03*
X849050Y481050D03*
X809384Y484984D03*
X800800Y526900D03*
X804584Y526584D03*
X829500Y481500D03*
X821050Y533350D03*
X813150Y533450D03*
X888551Y226649D03*
X882871Y243771D03*
X892449Y241249D03*
X886300Y221150D03*
X896969Y301500D03*
X883240Y301973D03*
X888668Y322100D03*
X886540Y388996D03*
X872750Y403400D03*
G54D23*
X64350Y582500D03*
X129100Y597100D03*
X141189Y596337D03*
X209445Y525049D03*
X148840Y555135D03*
X153495Y555166D03*
X228384Y627209D03*
X375600Y604200D03*
X349200Y637700D03*
X354000D03*
X685700Y309600D03*
X690620Y323740D03*
X697200Y547900D03*
X706506Y603099D03*
X794726Y368356D03*
X759900Y492400D03*
G54D14*
X70865Y98425D03*
Y472440D03*
X49213Y740157D03*
X314960Y472440D03*
X405511Y39370D03*
X364173Y740157D03*
X612204Y433070D03*
Y740157D03*
X875985Y59055D03*
X875984Y433070D03*
Y740157D03*
G54D41*
X99874Y535824D03*
X175548Y568251D03*
X186489Y582625D03*
X179600Y559200D03*
X185080Y615540D03*
X216950Y609150D03*
X379014Y629080D03*
X831200Y332500D03*
G54D50*
X339331Y49803D03*
X360669Y91929D03*
G54D32*
X140702Y492561D03*
X183100Y506500D03*
X170800D03*
X179000D03*
X155000Y499800D03*
X166700Y506500D03*
X187300Y506400D03*
X166861Y494320D03*
X146300Y499500D03*
X150500Y499780D03*
X179200Y528400D03*
X191000Y536000D03*
X202700Y536100D03*
X206800Y535980D03*
X205020Y612140D03*
X197191Y636588D03*
X192911Y636648D03*
X215658Y486933D03*
X266816Y564537D03*
X270836Y564519D03*
X246145Y561318D03*
X273490Y587802D03*
X228102Y532842D03*
X210900Y536000D03*
X335962Y705596D03*
X352480Y589564D03*
X365400Y576100D03*
X360300Y561800D03*
X347500Y709700D03*
X345654Y700015D03*
X375500Y707700D03*
X456400Y57800D03*
X512290Y57673D03*
X500411Y55265D03*
X490653Y64137D03*
X629500Y194200D03*
X656665Y301866D03*
X652465Y301966D03*
X732230Y311269D03*
X708300Y452700D03*
X750600Y492300D03*
X828800Y239300D03*
X815726Y367256D03*
G54D51*
X339331Y91929D03*
X360669Y49803D03*
G54D33*
X121330Y499550D03*
X81924Y558398D03*
X81925Y554363D03*
X101476Y560166D03*
X101444Y555240D03*
X153100Y460200D03*
X161930Y510140D03*
X177300Y517000D03*
X152965Y481057D03*
X153085Y468562D03*
X157388Y522134D03*
X157358Y517677D03*
X175802Y574058D03*
X151754Y588802D03*
X200890Y611700D03*
X172893Y635303D03*
X200160Y599340D03*
X187650Y607360D03*
X207190Y637250D03*
X201316Y620590D03*
X151457Y602562D03*
X227809Y558053D03*
X269312Y583809D03*
X227700Y585900D03*
X227775Y576816D03*
X227400Y571900D03*
X226600Y593200D03*
X246800Y531240D03*
X245600Y543100D03*
X249200Y606260D03*
X241550Y610860D03*
X215100Y642200D03*
X249765Y594250D03*
X238762Y606422D03*
X226600Y597200D03*
X236200Y637900D03*
X238810Y602160D03*
X236200Y642300D03*
X225492Y642006D03*
X320700Y552900D03*
X316100Y573000D03*
X312350Y658050D03*
X319900Y658100D03*
X347517Y575841D03*
X359496Y545220D03*
X367000Y540600D03*
X379116Y620503D03*
X365900Y664200D03*
X341600Y696100D03*
X379157Y695203D03*
X493179Y30448D03*
X510700Y65000D03*
X493200Y38500D03*
X483300Y58900D03*
Y62900D03*
X616686Y367271D03*
X711052Y261999D03*
X749100Y208500D03*
X824700Y240200D03*
X823500Y248200D03*
X824668Y235964D03*
X824700Y244200D03*
X814400Y257800D03*
X817900Y310400D03*
X835700Y353000D03*
G54D42*
X141887Y560491D03*
X144037Y549486D03*
X204700Y519400D03*
X195400Y519500D03*
X200055Y519351D03*
X146567Y560391D03*
X151257Y560423D03*
X181505Y575791D03*
X160964Y717468D03*
X214100Y519500D03*
X445900Y31900D03*
X507895Y54797D03*
X496000Y50615D03*
X706580Y316040D03*
G54D15*
X75373Y509879D03*
X75405Y517477D03*
X69878Y509777D03*
X69778Y517477D03*
X64251Y509877D03*
X64151Y517477D03*
X97900Y510000D03*
X92286Y517477D03*
X81032D03*
X97913D03*
X92273Y510000D03*
X81068Y509866D03*
X86673Y510000D03*
X86659Y517477D03*
X136702Y492561D03*
X127800Y618100D03*
X174900Y506500D03*
X191869Y506489D03*
X167000Y520500D03*
X199892Y503022D03*
X162800Y494300D03*
X162700Y520500D03*
X171200Y525800D03*
X186111Y520181D03*
X182600Y536000D03*
X145400D03*
X198600Y536200D03*
X186900Y536100D03*
X178600Y535800D03*
X174500D03*
X159300Y529700D03*
X156501Y564267D03*
X196890Y567300D03*
X200910Y563190D03*
X150067Y614143D03*
X266800Y575100D03*
X270947Y576404D03*
X228400Y567750D03*
X238100Y586400D03*
X215100Y536000D03*
X242100Y586400D03*
X219200Y536500D03*
X232500Y529200D03*
X242000Y594200D03*
X327174Y389318D03*
X310700Y562600D03*
X315290Y681870D03*
X349182Y381274D03*
X345244Y587260D03*
X369500Y576100D03*
X351900Y532300D03*
X380000Y601800D03*
X634000Y194200D03*
X730900Y194700D03*
X670200Y203300D03*
X768529Y199354D03*
X740100Y491484D03*
X735600D03*
X744600D03*
X806100Y225900D03*
X802100D03*
X818100D03*
X814100D03*
X810100D03*
G54D60*
G01X53302Y567317D02*
X53301Y567316D01*
X47668D01*
G01X697200Y542100D02*
Y529200D01*
X421653Y126378D03*
X435827D03*
X450000D03*
X464173D03*
X428740Y121654D03*
X442913D03*
X457086D03*
X471260D03*
X421653Y130709D03*
X428740Y125985D03*
X435827Y130709D03*
X442913Y125985D03*
X450000Y130709D03*
X457086Y125985D03*
X464173Y130709D03*
X471260Y125985D03*
X428740Y131496D03*
X442913D03*
X457086D03*
X471260D03*
X421653Y183071D03*
X435827D03*
X450000D03*
X464173D03*
X421653Y136221D03*
X435827D03*
X450000D03*
X464173D03*
X421653Y140551D03*
X428740Y135827D03*
X435827Y140551D03*
X442913Y135827D03*
X450000Y140551D03*
X457086Y135827D03*
X464173Y140551D03*
X471260Y135827D03*
X421653Y144882D03*
X428740Y140158D03*
X435827Y144882D03*
X442913Y140158D03*
X450000Y144882D03*
X457086Y140158D03*
X464173Y144882D03*
X471260Y140158D03*
X421653Y150394D03*
X428740Y145670D03*
X435827Y150394D03*
X442913Y145670D03*
X450000Y150394D03*
X457086Y145670D03*
X464173Y150394D03*
X471260Y145670D03*
X421653Y154725D03*
X428740Y150000D03*
X435827Y154725D03*
X442913Y150000D03*
X450000Y154725D03*
X457086Y150000D03*
X464173Y154725D03*
X471260Y150000D03*
X421653Y159055D03*
X428740Y154331D03*
X435827Y159055D03*
X442913Y154331D03*
X450000Y159055D03*
X457086Y154331D03*
X464173Y159055D03*
X471260Y154331D03*
X421653Y164567D03*
X428740Y159843D03*
X435827Y164567D03*
X442913Y159843D03*
X450000Y164567D03*
X457086Y159843D03*
X464173Y164567D03*
X471260Y159843D03*
X421653Y168898D03*
X428740Y164173D03*
X435827Y168898D03*
X442913Y164173D03*
X450000Y168898D03*
X457086Y164173D03*
X464173Y168898D03*
X471260Y164173D03*
X421653Y173229D03*
X428740Y168504D03*
X435827Y173229D03*
X442913Y168504D03*
X450000Y173229D03*
X457086Y168504D03*
X464173Y173229D03*
X471260Y168504D03*
X421653Y178740D03*
X428740Y174016D03*
X435827Y178740D03*
X442913Y174016D03*
X450000Y178740D03*
X457086Y174016D03*
X464173Y178740D03*
X471260Y174016D03*
X506693Y126378D03*
X520866D03*
X535039D03*
X513779Y121654D03*
X527953D03*
X506693Y130709D03*
X513779Y125985D03*
X520866Y130709D03*
X527953Y125985D03*
X535039Y130709D03*
X513779Y131496D03*
X527953D03*
X506693Y183071D03*
X520866D03*
X535039D03*
X506693Y136221D03*
X520866D03*
X535039D03*
X506693Y140551D03*
X513779Y135827D03*
X520866Y140551D03*
X527953Y135827D03*
X535039Y140551D03*
X506693Y144882D03*
X513779Y140158D03*
X520866Y144882D03*
X527953Y140158D03*
X535039Y144882D03*
X506693Y150394D03*
X513779Y145670D03*
X520866Y150394D03*
X527953Y145670D03*
X535039Y150394D03*
X506693Y154725D03*
X513779Y150000D03*
X520866Y154725D03*
X527953Y150000D03*
X535039Y154725D03*
X506693Y159055D03*
X513779Y154331D03*
X520866Y159055D03*
X527953Y154331D03*
X535039Y159055D03*
X506693Y164567D03*
X513779Y159843D03*
X520866Y164567D03*
X527953Y159843D03*
X535039Y164567D03*
X506693Y168898D03*
X513779Y164173D03*
X520866Y168898D03*
X527953Y164173D03*
X535039Y168898D03*
X506693Y173229D03*
X513779Y168504D03*
X520866Y173229D03*
X527953Y168504D03*
X535039Y173229D03*
X506693Y178740D03*
X513779Y174016D03*
X520866Y178740D03*
X527953Y174016D03*
X535039Y178740D03*
X549212Y126378D03*
X542126Y121654D03*
X556299D03*
X542126Y125985D03*
X549212Y130709D03*
X556299Y125985D03*
X542126Y131496D03*
X556299D03*
X549212Y183071D03*
Y136221D03*
X542126Y135827D03*
X549212Y140551D03*
X556299Y135827D03*
X542126Y140158D03*
X549212Y144882D03*
X556299Y140158D03*
X542126Y145670D03*
X549212Y150394D03*
X556299Y145670D03*
X542126Y150000D03*
X549212Y154725D03*
X556299Y150000D03*
X542126Y154331D03*
X549212Y159055D03*
X556299Y154331D03*
X542126Y159843D03*
X549212Y164567D03*
X556299Y159843D03*
X542126Y164173D03*
X549212Y168898D03*
X556299Y164173D03*
X542126Y168504D03*
X549212Y173229D03*
X556299Y168504D03*
X542126Y174016D03*
X549212Y178740D03*
X556299Y174016D03*
G54D24*
X64350Y576900D03*
X129100Y591500D03*
X141189Y590737D03*
X209445Y519449D03*
X148840Y549535D03*
X153495Y549566D03*
X228384Y621609D03*
X375600Y598600D03*
X349200Y632100D03*
X354000D03*
X685700Y304000D03*
X690620Y318140D03*
X697200Y542300D03*
X706506Y597499D03*
X794726Y362756D03*
X759900Y486800D03*
G54D25*
X49250Y580250D03*
X41868Y567316D03*
X96900Y712200D03*
X190450Y559250D03*
X194459Y577497D03*
X197030Y583440D03*
X185130Y552000D03*
X174460Y615380D03*
X694099Y607558D03*
X757500Y185200D03*
X789237Y202518D03*
X775000Y202500D03*
X803562Y202483D03*
G54D52*
X336282Y386493D03*
X332407Y393993D03*
X340157D03*
G54D34*
X126850Y490210D03*
Y487650D03*
Y485090D03*
X120350D03*
Y490210D03*
X320650Y514560D03*
Y512000D03*
Y509440D03*
X314150D03*
Y514560D03*
X369350Y522460D03*
Y519900D03*
Y517340D03*
X362850D03*
Y522460D03*
X364930Y534960D03*
Y532400D03*
Y529840D03*
X358430D03*
Y534960D03*
X382370Y706140D03*
Y708700D03*
Y711260D03*
X388870D03*
Y706140D03*
X354570Y702040D03*
Y704600D03*
Y707160D03*
X361070D03*
Y702040D03*
X354470Y689440D03*
Y692000D03*
Y694560D03*
X360970D03*
Y689440D03*
X573750Y64940D03*
Y67500D03*
X580250Y64940D03*
X573750Y70060D03*
X580250D03*
X551250Y69940D03*
Y72500D03*
Y75060D03*
X557750D03*
Y69940D03*
G54D70*
X699925Y313194D03*
Y324194D03*
X786600Y452500D03*
Y441500D03*
X777600Y452500D03*
Y441500D03*
G54D43*
X141887Y566091D03*
X144037Y555086D03*
X204700Y525000D03*
X195400Y525100D03*
X200055Y524951D03*
X146567Y565991D03*
X151257Y566023D03*
X181505Y581391D03*
X160964Y723068D03*
X214100Y525100D03*
X445900Y37500D03*
X507895Y60397D03*
X496000Y56215D03*
X706580Y321640D03*
G54D16*
X75373Y506479D03*
X75405Y514077D03*
X69878Y506377D03*
X69778Y514077D03*
X64251Y506477D03*
X64151Y514077D03*
X97900Y506600D03*
X92286Y514077D03*
X81032D03*
X97913D03*
X92273Y506600D03*
X81068Y506466D03*
X86673Y506600D03*
X86659Y514077D03*
X136702Y489161D03*
X127800Y614700D03*
X174900Y503100D03*
X191869Y503089D03*
X167000Y517100D03*
X199892Y499622D03*
X162800Y490900D03*
X162700Y517100D03*
X171200Y522400D03*
X159300Y526300D03*
X186111Y516781D03*
X182600Y532600D03*
X145400D03*
X198600Y532800D03*
X186900Y532700D03*
X178600Y532400D03*
X174500D03*
X156501Y560867D03*
X196890Y563900D03*
X200910Y559790D03*
X150067Y610743D03*
X232500Y525800D03*
X266800Y571700D03*
X270947Y573004D03*
X228400Y564350D03*
X238100Y583000D03*
X242000Y590800D03*
X215100Y532600D03*
X242100Y583000D03*
X219200Y533100D03*
X327174Y385918D03*
X310700Y559200D03*
X315290Y678470D03*
X349182Y377874D03*
X345244Y583860D03*
X369500Y572700D03*
X351900Y528900D03*
X380000Y598400D03*
X634000Y190800D03*
X670200Y199900D03*
X730900Y191300D03*
X768529Y195954D03*
X740100Y488084D03*
X735600D03*
X744600D03*
X806100Y222500D03*
X802100D03*
X818100D03*
X814100D03*
X810100D03*
G54D61*
X564803Y24409D03*
X574803D03*
X584803D03*
X753780D03*
X763780D03*
X773780D03*
X801024D03*
X811024D03*
X821024D03*
G54D80*
G01X164100Y572940D02*
Y556621D01*
X162597Y555118D01*
G54D71*
X733469Y481247D03*
G54D17*
X49306Y526995D03*
X41875D03*
X49306Y521269D03*
X41832Y521271D03*
X58500Y575850D03*
X54156Y571795D03*
X49306Y532622D03*
X41865Y532638D03*
X49385Y555153D03*
X41885D03*
X49306Y538249D03*
X41758Y538254D03*
X49306Y543876D03*
X41858Y543881D03*
X49385Y549526D03*
X41903Y549508D03*
X49385Y560879D03*
X41800Y560900D03*
X129170Y499350D03*
X130492Y602854D03*
X167000Y527700D03*
X153115Y464338D03*
Y472738D03*
X197715Y471838D03*
X153015Y476938D03*
X197815Y475938D03*
X175487Y587147D03*
X205440Y624780D03*
X185300Y635300D03*
X163900Y606760D03*
X207100Y641270D03*
X206600Y653100D03*
X200450Y607600D03*
X172902Y629826D03*
X215220Y491100D03*
X242000Y575100D03*
X241900Y558500D03*
X249700Y565900D03*
X241900Y550400D03*
X249717Y569957D03*
X269309Y587813D03*
X241900Y554400D03*
X241700Y562600D03*
Y566700D03*
X242000Y571000D03*
X249732Y579067D03*
X227548Y581666D03*
X243600Y539000D03*
X215200Y634500D03*
X225508Y637894D03*
X214508Y653294D03*
X334700Y512000D03*
X377200Y31000D03*
X374484Y626032D03*
X357000Y683400D03*
X347500Y687500D03*
X370500Y671900D03*
X457400Y33600D03*
X459900Y61900D03*
X441400Y37800D03*
X493194Y34455D03*
X713773Y253883D03*
X712379Y257964D03*
X689000Y265100D03*
X728530Y287930D03*
X689000Y269200D03*
X673400Y307400D03*
X779600Y182200D03*
X793473Y182318D03*
X764700Y180800D03*
X786390Y249880D03*
X807892Y182209D03*
X815628Y253664D03*
X817900Y314600D03*
G54D62*
X601500Y367550D03*
X598941D03*
X601500Y359650D03*
X598941D03*
X604059Y367550D03*
Y359650D03*
G54D35*
X100130Y576452D03*
X171969Y579940D03*
X201170Y552500D03*
X184120Y611240D03*
X222019Y634188D03*
X215720Y605070D03*
X211700Y638400D03*
X211100Y649500D03*
X321700Y681900D03*
X387800Y700700D03*
X368200Y689500D03*
X609700Y358900D03*
X722850Y256550D03*
X722550Y231460D03*
X722760Y225060D03*
X722700Y262300D03*
X730370Y227400D03*
X730360Y230840D03*
X723140Y249850D03*
X723370Y243700D03*
X722829Y237714D03*
X727350Y284210D03*
X723063Y268702D03*
X732520Y288150D03*
X725100Y275200D03*
X743050Y249900D03*
X771500Y233900D03*
X762300Y262250D03*
X777400Y214700D03*
X738300Y218800D03*
X745800D03*
X777400Y218100D03*
X784919Y218074D03*
X760900Y269000D03*
X746168Y294464D03*
X740060Y287810D03*
X800800Y246800D03*
G54D53*
X346457Y66850D03*
Y57007D03*
X353543Y70787D03*
Y62913D03*
Y55039D03*
X346457Y74724D03*
Y84567D03*
X353543Y86535D03*
Y78661D03*
G54D44*
G01X835600Y481500D02*
X829500D01*
X83000Y734600D03*
X838300Y36700D03*
X888800Y696900D03*
G54D26*
X54850Y580250D03*
X47468Y567316D03*
X102500Y712200D03*
X196050Y559250D03*
X200059Y577497D03*
X202630Y583440D03*
X190730Y552000D03*
X180060Y615380D03*
X699699Y607558D03*
X763100Y185200D03*
X794837Y202518D03*
X780600Y202500D03*
X809162Y202483D03*
G54D81*
G01X75405Y514027D02*
Y509961D01*
X75373Y509929D01*
G01X86750Y542368D02*
X83555D01*
X79200Y538013D01*
Y527960D01*
X79700Y527460D01*
X81964D01*
X82464Y526960D01*
Y525960D01*
X81964Y525460D01*
X79700D01*
X79200Y524960D01*
Y524328D01*
X78155Y523283D01*
Y516387D01*
X75795Y514027D01*
X75405D01*
G01X64151D02*
Y510027D01*
X64251Y509927D01*
G01X81276Y548766D02*
Y545376D01*
X76000Y540100D01*
Y535061D01*
X72337Y531398D01*
Y529015D01*
X66901Y523579D01*
Y516387D01*
X64541Y514027D01*
X64151D01*
G01X45856Y521269D02*
Y521659D01*
X48442Y524245D01*
X57237D01*
X57737Y523745D01*
Y521754D01*
X58237Y521254D01*
X59237D01*
X59737Y521754D01*
Y523745D01*
X60237Y524245D01*
X62355D01*
X74076Y535966D01*
G01X41882Y521271D02*
X45854D01*
X45856Y521269D01*
G01X69778Y514027D02*
Y509927D01*
X69878Y509827D01*
G01X69778Y514027D02*
X70528Y514777D01*
X70918D01*
X72528Y516387D01*
Y522540D01*
X76586Y526598D01*
Y528496D01*
X76086Y528996D01*
X75134D01*
X74634Y529496D01*
Y530496D01*
X75134Y530996D01*
X76086D01*
X76586Y531496D01*
Y532690D01*
X77500Y533604D01*
Y539418D01*
X83600Y545518D01*
G01X45856Y526995D02*
Y527856D01*
X47745Y529745D01*
X58156D01*
X58656Y529245D01*
Y527128D01*
X59156Y526628D01*
X60156D01*
X60656Y527128D01*
Y529245D01*
X61156Y529745D01*
X63845D01*
X71669Y537569D01*
X71686D01*
X72652Y538535D01*
Y538552D01*
X75508Y541408D01*
Y542198D01*
G01X41925Y526995D02*
X45856D01*
G01X41250Y494600D02*
X43350Y492500D01*
X58050D01*
X62450Y496900D01*
X101370D01*
X104670Y500200D01*
X112504D01*
X112543Y500196D01*
X117234D01*
X117880Y499550D01*
G01X45935Y549526D02*
X41971D01*
X41953Y549508D01*
G01X74151Y545516D02*
Y547064D01*
X74910Y547823D01*
X76976D01*
X77390Y548237D01*
Y549476D01*
X76863Y550003D01*
X72497D01*
X71050Y551450D01*
X64750D01*
X63924Y552276D01*
X61982D01*
X60488Y553770D01*
X54910D01*
X53416Y552276D01*
X48295D01*
X45935Y549916D01*
Y549526D01*
G01Y555153D02*
X41935D01*
G01X74498Y551757D02*
X73855Y552400D01*
X65500D01*
X64724Y553176D01*
X62966D01*
X60490Y555652D01*
X59824D01*
X58819Y556657D01*
Y560525D01*
X58319Y561025D01*
X57319D01*
X56819Y560525D01*
Y557760D01*
X55952Y556893D01*
X54587D01*
X53577Y557903D01*
X46773D01*
X45935Y557065D01*
Y555153D01*
G01X71002Y539219D02*
X66540Y534757D01*
X63287D01*
X62787Y534257D01*
Y532317D01*
X62287Y531817D01*
X61287D01*
X60787Y532317D01*
Y534257D01*
X60287Y534757D01*
X59287D01*
X58787Y534257D01*
Y532317D01*
X58287Y531817D01*
X57287D01*
X56787Y532317D01*
Y534257D01*
X56287Y534757D01*
X55438D01*
X54696Y535499D01*
X47399D01*
X45856Y533956D01*
Y532622D01*
G01X41915Y532638D02*
X45840D01*
X45856Y532622D01*
G01X71002Y542368D02*
X69320Y544050D01*
X58292D01*
X57533Y544809D01*
Y551250D01*
X57079Y551704D01*
X56079D01*
X55533Y551158D01*
Y547243D01*
X55033Y546743D01*
X47149D01*
X45856Y545450D01*
Y543876D01*
G01X41908Y543881D02*
X45851D01*
X45856Y543876D01*
G01X41808Y538254D02*
X45851D01*
X45856Y538249D01*
G01D02*
Y539893D01*
X46962Y540999D01*
X55625D01*
X56079Y540545D01*
Y537645D01*
X56579Y537145D01*
X57579D01*
X58079Y537645D01*
Y541555D01*
X58510Y541986D01*
X59510D01*
X60079Y541417D01*
Y537645D01*
X60579Y537145D01*
X61579D01*
X62079Y537645D01*
Y540088D01*
X62691Y540700D01*
X66371D01*
X67852Y539219D01*
G01X54206Y571795D02*
Y575006D01*
X55050Y575850D01*
G01X54206Y571795D02*
X54472Y571529D01*
X57305D01*
X57805Y571029D01*
Y567221D01*
X58305Y566721D01*
X59305D01*
X59805Y567221D01*
Y571029D01*
X60305Y571529D01*
X61343D01*
X63050Y569822D01*
G01X45935Y560879D02*
Y562704D01*
X46860Y563629D01*
X58505D01*
X58802Y563332D01*
X59510D01*
X61351Y565173D01*
X62059D01*
X62766Y564466D01*
Y563758D01*
X60925Y561917D01*
Y561209D01*
X61535Y560599D01*
Y559296D01*
X65106Y555725D01*
Y555380D01*
X67169Y553317D01*
X69352D01*
X71002Y554967D01*
G01X41850Y560900D02*
X45914D01*
X45935Y560879D01*
G01X302175Y521026D02*
Y519798D01*
X284755Y502378D01*
X250931D01*
X205422Y456869D01*
X145131D01*
X143100Y458900D01*
X120105D01*
X114390Y453185D01*
G01X373222Y535938D02*
Y533278D01*
X376998Y529502D01*
Y511654D01*
X370644Y505300D01*
X367536D01*
X358741Y496505D01*
X346717D01*
X346262Y496050D01*
X336496D01*
X328646Y503900D01*
X295520D01*
X292439Y500819D01*
X251494D01*
X206010Y455335D01*
X144543D01*
X142478Y457400D01*
X122349D01*
X118108Y453159D01*
G01X370247Y546218D02*
X370333Y546132D01*
X371517D01*
X375350Y542299D01*
Y536770D01*
X375352Y535978D01*
Y535048D01*
X378498Y531902D01*
Y510675D01*
X371623Y503800D01*
X368683D01*
X359888Y495005D01*
X347339D01*
X346884Y494550D01*
X335874D01*
X328024Y502400D01*
X298122D01*
X290222Y494500D01*
X265278D01*
X262078Y491300D01*
X244152D01*
X206687Y453835D01*
X143921D01*
X141856Y455900D01*
X124570D01*
X121826Y453156D01*
G01X370223Y549965D02*
X373079D01*
X376876Y546168D01*
Y536925D01*
X379998Y533803D01*
Y509598D01*
X375850Y505450D01*
Y501858D01*
X374564Y500572D01*
X373948D01*
X366881Y493505D01*
X347961D01*
X347506Y493050D01*
X335252D01*
X327402Y500900D01*
X298744D01*
X290844Y493000D01*
X265900D01*
X262700Y489800D01*
X244774D01*
X207309Y452335D01*
X143299D01*
X141517Y454117D01*
X130344D01*
X128968Y452741D01*
G01X384950Y551876D02*
X382999Y549925D01*
Y543539D01*
X384498Y542040D01*
Y533444D01*
X387537Y530405D01*
Y511110D01*
X385082Y508655D01*
Y495680D01*
X379052Y489650D01*
X373072D01*
X370022Y486600D01*
X335336D01*
X325536Y496400D01*
X300610D01*
X288710Y484500D01*
X245976D01*
X209042Y447566D01*
X130172D01*
X125353Y452385D01*
G01X384950Y555276D02*
X384356D01*
X380750Y551670D01*
Y543666D01*
X382998Y541418D01*
Y520469D01*
X386037Y517430D01*
Y511732D01*
X383582Y509277D01*
Y496302D01*
X378430Y491150D01*
X372450D01*
X369400Y488100D01*
X335958D01*
X326158Y497900D01*
X299988D01*
X288588Y486500D01*
X245718D01*
X208318Y449100D01*
X134208D01*
X132109Y451199D01*
G01X383056Y563675D02*
X380250D01*
X379250Y562675D01*
Y543044D01*
X381498Y540796D01*
Y519523D01*
X384537Y516484D01*
Y512354D01*
X382082Y509899D01*
Y502904D01*
X368778Y489600D01*
X336580D01*
X326780Y499400D01*
X299366D01*
X287966Y488000D01*
X245096D01*
X207852Y450756D01*
X142756D01*
X140895Y452617D01*
X137244D01*
X136021Y451394D01*
G01X358800Y478000D02*
X340400D01*
X324500Y493900D01*
X301646D01*
X289746Y482000D01*
X247012D01*
X210078Y445066D01*
X127812D01*
G01X86659Y514027D02*
Y510064D01*
X86673Y510050D01*
G01X86750Y539218D02*
Y533117D01*
X87250Y532617D01*
X88612D01*
X89112Y532117D01*
Y531117D01*
X88612Y530617D01*
X87250D01*
X86750Y530117D01*
Y529117D01*
X87250Y528617D01*
X92062D01*
X92648Y528031D01*
Y527203D01*
X92062Y526617D01*
X88111D01*
X87462Y525968D01*
Y524385D01*
X89409Y522438D01*
Y516387D01*
X87799Y514777D01*
X87409D01*
X86659Y514027D01*
G01X97913D02*
Y510063D01*
X97900Y510050D01*
G01X97913Y514027D02*
X98663Y514777D01*
X99053D01*
X101890Y517614D01*
Y530072D01*
X100337Y531625D01*
X95957D01*
X94250Y533332D01*
Y538250D01*
X89899Y542601D01*
Y545518D01*
G01X92286Y514027D02*
Y510063D01*
X92273Y510050D01*
G01X89899Y539218D02*
Y537664D01*
X89399Y537164D01*
X88338D01*
X87838Y536664D01*
Y535664D01*
X88338Y535164D01*
X89399D01*
X89899Y534664D01*
Y533642D01*
X95036Y528505D01*
Y527270D01*
X95536Y526770D01*
X99237D01*
X99823Y526184D01*
Y525356D01*
X99237Y524770D01*
X95536D01*
X95036Y524270D01*
Y516387D01*
X92676Y514027D01*
X92286D01*
G01X81032D02*
X81782Y514777D01*
X82172D01*
X83782Y516387D01*
Y522894D01*
X84622Y523734D01*
Y529272D01*
X84122Y529772D01*
X81449D01*
X80949Y530272D01*
Y531272D01*
X81449Y531772D01*
X84122D01*
X84622Y532272D01*
Y533272D01*
X84122Y533772D01*
X81449D01*
X80949Y534272D01*
Y535272D01*
X81449Y535772D01*
X84122D01*
X84622Y536272D01*
Y538197D01*
X83600Y539219D01*
G01X81068Y509916D02*
Y513991D01*
X81032Y514027D01*
G01X205516Y467968D02*
X206300Y468752D01*
Y475700D01*
X203800Y478200D01*
X188871D01*
X182271Y484800D01*
X158129D01*
X156328Y482999D01*
X154672D01*
X154614Y483057D01*
X151405D01*
X150462Y484000D01*
X141107D01*
G01X116500Y477000D02*
X120600Y481100D01*
X134200D01*
X137100Y484000D01*
X141107D01*
G01X144500Y489500D02*
X143550Y490450D01*
Y503740D01*
X145160Y505350D01*
X147440D01*
X148157Y504633D01*
X162353D01*
X164038Y506318D01*
Y514088D01*
X167000Y517050D01*
G01X120350Y485090D02*
X117860D01*
X114500Y488450D01*
Y490000D01*
G01X136702Y489111D02*
X132899D01*
G01X140702D02*
X136702D01*
G01X132899D02*
X130629D01*
X129168Y487650D01*
X126850D01*
G01X140702Y489111D02*
X143768Y486045D01*
X146216D01*
G01X129220Y499350D02*
X130424D01*
X132774Y497000D01*
G01X125720Y499350D02*
X121580D01*
X121380Y499550D01*
G01X125720Y499350D02*
X126950Y498120D01*
Y495528D01*
G01D02*
Y490310D01*
X126850Y490210D01*
G01X98026Y560166D02*
X95101D01*
X91158Y556223D01*
Y552411D01*
X91879Y551690D01*
X99850D01*
X100350Y551190D01*
Y550190D01*
X99850Y549690D01*
X88875D01*
X86750Y551815D01*
G01X101494Y555240D02*
Y555670D01*
X98026Y559138D01*
Y560166D01*
G01X127401Y606930D02*
Y614251D01*
X127800Y614650D01*
G01X142447Y611714D02*
X142430Y611697D01*
Y604051D01*
X142440Y604041D01*
Y603860D01*
X144950Y601350D01*
Y597400D01*
X145710Y596640D01*
G01X129800Y630700D02*
X139550D01*
X143899Y635049D01*
X148489D01*
X151760Y638320D01*
X160540D01*
X163350Y635510D01*
Y635486D01*
X163501Y635335D01*
Y629499D01*
X165644Y627356D01*
X170482D01*
X172952Y629826D01*
G01X130542Y602854D02*
X133554D01*
X134700Y604000D01*
G01D02*
Y605100D01*
X133100Y606700D01*
X130800D01*
G01X190278Y459865D02*
X192634Y462221D01*
X193721D01*
X202190Y470690D01*
Y471014D01*
G01X202271Y475938D02*
X202762D01*
X204300Y474400D01*
Y469731D01*
X194368Y459799D01*
X193686D01*
G01X153150Y460200D02*
X153165Y460215D01*
Y464338D01*
G01X171492Y496413D02*
X168550Y499355D01*
Y504850D01*
X166850Y506550D01*
X166700D01*
G01X166600Y509800D02*
X166700Y509700D01*
Y506550D01*
G01Y499800D02*
Y496335D01*
X166861Y496174D01*
Y494370D01*
G01X166700Y503050D02*
Y499800D01*
G01X166861Y494370D02*
X166841Y494350D01*
X162800D01*
G01D02*
Y494900D01*
X159400Y498300D01*
G01X190416Y498361D02*
X190116Y498061D01*
X188439D01*
X187000Y499500D01*
G01X190416Y498361D02*
Y499834D01*
X187300Y502950D01*
G01X146300Y496050D02*
Y492700D01*
X146500Y492500D01*
G01X145400Y524046D02*
Y532550D01*
G01X183100Y506550D02*
X182874Y506776D01*
Y508926D01*
X182300Y509500D01*
Y509600D01*
G01X187300Y506450D02*
X187170Y506580D01*
X183130D01*
X183100Y506550D01*
G01X202190Y471014D02*
X201366Y471838D01*
X197765D01*
G01X197865Y475938D02*
X202271D01*
G01X179200Y528450D02*
X183320D01*
X184780Y526990D01*
G01X155000Y496350D02*
Y490900D01*
X154500Y490400D01*
Y487000D01*
G01X179000Y506550D02*
Y509662D01*
X178869Y509793D01*
G01X209800Y478500D02*
X204750Y483550D01*
X203950D01*
X198070Y489430D01*
Y493520D01*
X199892Y495342D01*
Y499572D01*
G01X155000Y499850D02*
X157909D01*
X158509Y500450D01*
X162030D01*
X162530Y500950D01*
G01X150500Y499830D02*
X154980D01*
X155000Y499850D01*
G01X162530Y500950D02*
Y501944D01*
X162029Y502445D01*
X158355D01*
X158290Y502380D01*
G01X169200Y534900D02*
X170900Y533200D01*
Y526150D01*
X171200Y525850D01*
G01X170800Y506550D02*
X170700Y506650D01*
Y509800D01*
G01X174900Y506550D02*
X170800D01*
G01Y503050D02*
Y500200D01*
X170900Y500100D01*
Y500000D01*
G01X162700Y520550D02*
X167000D01*
G01D02*
Y523000D01*
X165900Y524100D01*
G01X209256Y467946D02*
Y475644D01*
X204700Y480200D01*
X189700D01*
X182859Y487041D01*
X171571D01*
G01X144500Y489500D02*
X147791D01*
X152234Y485057D01*
X155557D01*
X157541Y487041D01*
X171571D01*
G01X176800Y492200D02*
Y495900D01*
G01X177350Y517000D02*
X176900Y516550D01*
Y497700D01*
X176800Y497600D01*
Y495900D01*
G01X173850Y517000D02*
X175700Y518850D01*
Y521000D01*
G01X175805Y524073D02*
X175700Y523968D01*
Y521000D01*
G01X199881Y507507D02*
Y503083D01*
X199892Y503072D01*
G01X206180Y509524D02*
X205500D01*
X205424Y509600D01*
X201974D01*
X199881Y507507D01*
G01X186111Y516731D02*
X192169D01*
X195149Y513751D01*
G01X203065Y493980D02*
Y486935D01*
X204950Y485050D01*
X207732D01*
X212293Y480489D01*
X213359D01*
G01X150500Y496330D02*
Y493000D01*
G01X214040Y504230D02*
X211692D01*
X210502Y505420D01*
X206454D01*
X203692Y502658D01*
Y494607D01*
X203065Y493980D01*
G01X190950Y482100D02*
Y494850D01*
X193000Y496900D01*
Y501908D01*
X191869Y503039D01*
G01X153065Y476938D02*
X158000D01*
G01X153015Y481057D02*
Y476988D01*
X153065Y476938D01*
G01X158000D02*
X158562D01*
X162267Y473233D01*
X165382D01*
G01X153135Y468562D02*
X153165Y468592D01*
Y472738D01*
G01X157800Y471800D02*
X158927Y470673D01*
X165382D01*
G01X153165Y472738D02*
X153527Y473100D01*
X156500D01*
X157800Y471800D01*
G01X165382Y468113D02*
X159213D01*
X158200Y467100D01*
G01D02*
X155438Y464338D01*
X153165D01*
G01X193238Y465985D02*
X191815D01*
X187127Y470673D01*
X181562D01*
G01Y473233D02*
X188167D01*
X189500Y471900D01*
G01X194265Y471838D02*
X189562D01*
X189500Y471900D01*
G01X181562Y475793D02*
X189993D01*
X190200Y476000D01*
G01X194365Y475938D02*
X190262D01*
X190200Y476000D01*
G01X161980Y510140D02*
Y509090D01*
X159480Y506590D01*
G01X158480Y510140D02*
X154700D01*
X154660Y510100D01*
G01X155540Y506510D02*
X153950Y508100D01*
Y509390D01*
X154660Y510100D01*
G01X195300Y498900D02*
X195900Y499500D01*
Y503600D01*
G01X191869Y506539D02*
X194561D01*
X195900Y505200D01*
Y503600D01*
G01X152584Y532922D02*
X153938Y531568D01*
Y526490D01*
G01Y522134D02*
Y526490D01*
G01X150162Y525937D02*
Y524364D01*
X152392Y522134D01*
X153938D01*
G01X149093Y541418D02*
X147429Y539754D01*
Y524156D01*
X153908Y517677D01*
G01D02*
X150341D01*
X148527Y519491D01*
G01X191725Y523074D02*
Y520653D01*
X190603Y519531D01*
G01D02*
X186811D01*
X186111Y520231D01*
G01X202380Y567970D02*
X201750Y567340D01*
Y564080D01*
X200910Y563240D01*
G01X196890Y563850D02*
X198939D01*
X199550Y563239D01*
X199551Y563240D01*
X200910D01*
G01X196250Y559250D02*
Y563210D01*
X196890Y563850D01*
G01X202380Y567970D02*
X205092Y570682D01*
Y572416D01*
X206692Y574016D01*
G01X190945Y542519D02*
X191400Y542064D01*
Y540000D01*
X191100Y539700D01*
G01X186900Y536150D02*
X187550D01*
X191100Y539700D01*
G01X202700Y532650D02*
Y530307D01*
X203610Y529397D01*
G01X172047Y545647D02*
X170497Y544097D01*
Y541876D01*
X170545Y541828D01*
Y539779D01*
G01X159449Y545671D02*
X157849Y544071D01*
X154001D01*
X153624Y543694D01*
G01X162599Y545669D02*
X161049Y544119D01*
Y541151D01*
X161300Y540900D01*
Y535450D01*
X161750Y535000D01*
G01X165749Y545669D02*
X167299Y544119D01*
Y541439D01*
X165030Y539170D01*
G01X178600Y535850D02*
Y538001D01*
X180540Y539941D01*
G01X184646Y545671D02*
X183046Y544071D01*
Y541877D01*
X183045Y541876D01*
Y541781D01*
X182045Y540781D01*
X181380D01*
X180540Y539941D01*
G01X187600Y542450D02*
X186950Y543100D01*
X185226D01*
X184645Y542519D01*
G01X187600Y542450D02*
Y540076D01*
X183574Y536050D01*
X182600D01*
G01X202700Y536150D02*
Y541426D01*
X203900Y542626D01*
G01D02*
X206587D01*
X206692Y542521D01*
G01X212991Y583465D02*
X211426Y581900D01*
X209234D01*
X209199Y581865D01*
X209198D01*
X208291Y580958D01*
Y578491D01*
X206900Y577100D01*
G01X209841Y577165D02*
Y576391D01*
X208291Y574841D01*
Y571331D01*
X207820Y570860D01*
G01X145150Y540250D02*
Y536300D01*
X145400Y536050D01*
G01X145150Y540250D02*
Y541200D01*
X149900Y545950D01*
X156020D01*
X156299Y545671D01*
G01X182600Y532550D02*
Y530600D01*
X183100Y530100D01*
X184690D01*
X184830Y529960D01*
G01X178600Y532350D02*
Y529050D01*
X179200Y528450D01*
G01X194094Y599213D02*
X192543Y597662D01*
Y595420D01*
X193450Y594513D01*
X194686D01*
X195643Y593556D01*
Y592320D01*
X196600Y591363D01*
X197886D01*
X198843Y592320D01*
Y593556D01*
X199800Y594513D01*
X201036D01*
X201943Y595420D01*
Y601230D01*
X201000Y602173D01*
Y603600D01*
G01X175197Y545671D02*
X176747Y544121D01*
Y540901D01*
X175545Y539699D01*
G01X174500Y535850D02*
Y538654D01*
X175545Y539699D01*
G01X167050Y527700D02*
X165085Y529665D01*
Y532153D01*
G01D02*
Y534931D01*
X162599Y537417D01*
Y542519D01*
G01X169200Y534900D02*
X168395Y535705D01*
Y542016D01*
X168898Y542519D01*
G01X156299Y542521D02*
X159327Y539493D01*
Y539484D01*
G01X159300Y529750D02*
X159327Y529777D01*
Y539484D01*
G01X216141Y599212D02*
X214645Y597716D01*
X214338D01*
X214284Y597662D01*
X213633D01*
X210434Y594463D01*
X209198D01*
X208291Y593556D01*
Y591791D01*
X206692Y590192D01*
Y589763D01*
G01X148304Y588802D02*
Y594046D01*
X145710Y596640D01*
G01X151804Y588802D02*
Y593074D01*
X152170Y593440D01*
G01X194093Y592913D02*
Y589764D01*
G01X206692Y586614D02*
Y587264D01*
X208267Y588839D01*
Y590381D01*
X209248Y591362D01*
X213636D01*
X214757Y592483D01*
Y594104D01*
X215519Y594866D01*
G01X156501Y564317D02*
Y567965D01*
G01D02*
X157835Y569299D01*
X161031D01*
X162598Y570866D01*
G01X165748Y599213D02*
Y598256D01*
X167348Y596656D01*
Y595420D01*
X168305Y594463D01*
X169541D01*
X170448Y593556D01*
Y592270D01*
X169492Y591314D01*
X156733D01*
X156391Y590972D01*
G01X191000Y536050D02*
X194493D01*
X194942Y536499D01*
G01X194094Y542519D02*
X195644Y540969D01*
Y537201D01*
X194942Y536499D01*
G01X200393Y548819D02*
X201991Y547221D01*
X210167D01*
X210169Y547219D01*
X210485D01*
X211335Y546369D01*
X211350D01*
X211442Y546277D01*
Y543163D01*
X211441Y543162D01*
Y540159D01*
X212000Y539600D01*
G01X199700Y541100D02*
Y537350D01*
X198600Y536250D01*
G01X199700Y541100D02*
Y544976D01*
X200393Y545669D01*
G01X198600Y532750D02*
X199400Y531950D01*
Y529400D01*
G01X206800Y532530D02*
Y530800D01*
X207500Y530100D01*
Y529800D01*
X208000Y529300D01*
G01X206692Y545671D02*
X208859Y543504D01*
Y541759D01*
X206700Y539600D01*
G01X206800Y536030D02*
Y539500D01*
X206700Y539600D01*
G01X149093Y541418D02*
X151011D01*
X152415Y540014D01*
G01X190500Y547100D02*
X192663D01*
X194094Y545669D01*
G01X178100Y548700D02*
X179529Y547271D01*
X186529D01*
X189731Y544069D01*
X196031D01*
X197244Y542856D01*
Y542520D01*
G01X216000Y626900D02*
Y622400D01*
X215211Y621611D01*
Y618831D01*
X214795Y618415D01*
Y617495D01*
X207990Y610690D01*
Y605890D01*
X205142Y603042D01*
Y597613D01*
X206692Y596063D01*
G01X203542Y592913D02*
X205092Y594463D01*
X207285D01*
X208242Y595420D01*
Y599872D01*
X209290Y600920D01*
Y609868D01*
X216295Y616873D01*
Y617793D01*
X216711Y618209D01*
Y620611D01*
X218425Y622325D01*
Y627350D01*
X218000Y627775D01*
Y630400D01*
G01X196500Y603912D02*
X193451D01*
X192544Y603005D01*
Y600812D01*
X190945Y599213D01*
G01X200500Y607600D02*
X196812Y603912D01*
X196500D01*
G01X197866Y620590D02*
X198001Y620455D01*
Y616801D01*
X197300Y616100D01*
G01X190944Y596063D02*
Y596386D01*
X189360Y597970D01*
Y600462D01*
X190245Y601347D01*
Y602275D01*
X191660Y603690D01*
X191790D01*
X194700Y606600D01*
Y613500D01*
X197300Y616100D01*
G01X187796Y599212D02*
Y600171D01*
X189345Y601720D01*
Y603085D01*
X193560Y607300D01*
Y614020D01*
X195100Y615560D01*
Y617100D01*
X195866Y617866D01*
Y622495D01*
X198086Y624715D01*
G01X192911Y633198D02*
X197131D01*
X197191Y633138D01*
G01D02*
X197525D01*
X201250Y629413D01*
Y627879D01*
X198086Y624715D01*
G01X181850Y635300D02*
Y634040D01*
X178140Y630330D01*
G01X177378Y637409D02*
X179741D01*
X181850Y635300D01*
G01X177378Y637409D02*
X175049D01*
X172943Y635303D01*
G01X150790Y598540D02*
X153267Y596063D01*
X159448D01*
G01X151507Y602562D02*
X150790Y601845D01*
Y598540D01*
G01X168898Y596063D02*
Y597020D01*
X167298Y598620D01*
Y599856D01*
X164554Y602600D01*
X163300D01*
G01D02*
X160450Y605450D01*
Y606760D01*
G01X163200Y610070D02*
X163950Y609320D01*
Y606760D01*
G01X150067Y610693D02*
X150162D01*
X154443Y606412D01*
Y606411D01*
X156669Y604185D01*
G01D02*
X160998Y599856D01*
Y598620D01*
X162005Y597613D01*
X163241D01*
X164198Y596656D01*
Y595420D01*
X165105Y594513D01*
X166982D01*
X167932Y593563D01*
X168248D01*
X168898Y592913D01*
G01X150067Y614193D02*
X150214Y614340D01*
X153390D01*
X153720Y614010D01*
G01D02*
X156530Y611200D01*
X159390D01*
X160420Y610170D01*
G01X211058Y653294D02*
X206844D01*
X206650Y653100D01*
G01X213161Y623100D02*
Y622929D01*
X211050Y620818D01*
Y615250D01*
X206770Y610970D01*
Y606422D01*
X203542Y603194D01*
Y602362D01*
G01X209093Y615849D02*
Y620983D01*
X211111Y623001D01*
Y626228D01*
X207589Y629750D01*
X207569D01*
G01X207300Y633450D02*
Y630039D01*
X207569Y629770D01*
Y629750D01*
G01X207150Y641270D02*
Y637340D01*
X207240Y637250D01*
G01D02*
Y633510D01*
X207300Y633450D01*
G01X201000Y603600D02*
Y605200D01*
X203270Y607470D01*
Y610440D01*
X205020Y612190D01*
G01X162598Y596063D02*
X161048Y594513D01*
X153243D01*
X152170Y593440D01*
G01X194093Y592913D02*
X193393Y593613D01*
X193077D01*
X192220Y594470D01*
X190020D01*
X189158Y595332D01*
Y595533D01*
X187671Y597020D01*
X187470D01*
X186245Y598245D01*
Y602255D01*
X185246Y603254D01*
G01X184170Y611240D02*
Y607390D01*
X184200Y607360D01*
G01X184170Y611240D02*
Y614830D01*
X184880Y615540D01*
G01X184910Y622020D02*
Y615570D01*
X184880Y615540D01*
G01X185246Y603254D02*
X184200Y604300D01*
Y607360D01*
G01X148007Y602562D02*
X148000Y602569D01*
Y606650D01*
G01X144750Y606350D02*
X145450Y607050D01*
X147600D01*
X148000Y606650D01*
G01X168898Y599213D02*
Y600462D01*
X166780Y602580D01*
Y608824D01*
X161497Y614107D01*
X158862D01*
G01X155343Y609168D02*
Y608269D01*
X158619Y604993D01*
Y604180D01*
X161898Y600901D01*
Y599913D01*
X162598Y599213D01*
G01X155660Y599140D02*
X159375D01*
X159448Y599213D01*
G01X170200Y603600D02*
X173600Y600200D01*
Y597615D01*
X172048Y596063D01*
G01X177750Y603250D02*
X179900Y601100D01*
Y597618D01*
X178346Y596064D01*
G01X200940Y611700D02*
X204800Y615560D01*
Y617440D01*
G01X197000Y607600D02*
X199795Y610395D01*
Y610555D01*
X200940Y611700D01*
G01X201366Y620590D02*
Y624156D01*
X201990Y624780D01*
G01X201366Y620590D02*
X204092D01*
X204642Y621140D01*
G01X177300Y626800D02*
X175978D01*
X172952Y629826D01*
G01X161000Y634300D02*
Y619413D01*
X163478Y616935D01*
Y614678D01*
X168862Y609293D01*
Y608733D01*
X173676Y603919D01*
Y602927D01*
X176747Y599856D01*
Y595420D01*
X175197Y593870D01*
Y592913D01*
G01X157200Y634200D02*
X158000Y633400D01*
Y618877D01*
X167680Y609197D01*
Y602953D01*
X170448Y600185D01*
Y595102D01*
X172048Y593502D01*
Y592913D01*
G01X249090Y676611D02*
X245928D01*
X241482Y672165D01*
X235107D01*
X230072Y677200D01*
X183600D01*
X181700Y679100D01*
X181300D01*
G01X190200Y671000D02*
X191360Y672160D01*
X228040D01*
X233035Y667165D01*
X247115D01*
X247500Y667550D01*
X267933D01*
X270583Y664900D01*
X275017D01*
X286000Y675883D01*
Y677747D01*
X289935Y681682D01*
X303800D01*
G01X187500Y673100D02*
X189060Y674660D01*
X229076D01*
X234071Y669665D01*
X244498D01*
X247058Y672225D01*
X259000D01*
G01X299107Y177740D02*
X298468D01*
X293272Y182936D01*
Y183284D01*
X293270Y183286D01*
Y384110D01*
X301950Y392790D01*
X315496D01*
X316806Y394100D01*
X320467D01*
X331267Y404900D01*
Y423033D01*
X317900Y436400D01*
X297700D01*
X291100Y443000D01*
X271050D01*
X268900Y445150D01*
G01X228700Y450600D02*
X246500Y468400D01*
X276329D01*
X286134Y458595D01*
Y458066D01*
X286700Y457500D01*
G01X228700Y450600D02*
X224500Y446400D01*
Y445600D01*
G01X254900Y453900D02*
X259350Y449450D01*
X273150D01*
X277900Y444700D01*
X294371D01*
X300780Y438291D01*
X351455D01*
X363127Y426619D01*
Y426473D01*
X364577Y425023D01*
G01X238500Y448250D02*
X254350D01*
X258100Y444500D01*
X263800D01*
X267400Y440900D01*
X290400D01*
X296800Y434500D01*
X315700D01*
X329141Y421059D01*
Y405781D01*
X319473Y396113D01*
X316697D01*
X314874Y394290D01*
X301328D01*
X291770Y384732D01*
Y177106D01*
X295462Y173414D01*
G01X238500Y448250D02*
X235850D01*
X233200Y445600D01*
X232200D01*
G01X219800Y445700D02*
X246250Y472150D01*
X276167D01*
X277250Y471067D01*
Y469601D01*
X302751Y444100D01*
X302781D01*
X303090Y443791D01*
X353735D01*
X375088Y422438D01*
Y376957D01*
X370662Y372531D01*
X367358D01*
G01X213874Y445226D02*
X245048Y476400D01*
X276400D01*
X279400Y473400D01*
Y469573D01*
X303373Y445600D01*
X303403D01*
X303712Y445291D01*
X354357D01*
X376588Y423060D01*
Y376335D01*
X369373Y369120D01*
X367471D01*
G01X215658Y483483D02*
Y478858D01*
X213100Y476300D01*
G01X242500Y523500D02*
X237800D01*
X235541Y525759D01*
Y527780D01*
X234071Y529250D01*
X232500D01*
G01X213100Y472900D02*
X217200D01*
X222508Y478208D01*
Y479092D01*
G01D02*
X222500Y479100D01*
Y496500D01*
X221270Y497730D01*
X219160D01*
G01X258100Y516400D02*
X257080D01*
X254986Y514306D01*
X241947D01*
G01X227500Y512200D02*
X229606Y514306D01*
X241947D01*
G01X253700Y531240D02*
X258503D01*
X265148Y524595D01*
G01X267800Y479900D02*
X268300Y479400D01*
X275200D01*
X276700Y477900D01*
X281900D01*
X283300Y476500D01*
X283360D01*
X290400Y469460D01*
Y467090D01*
X306199Y451291D01*
X323723D01*
X342932Y470500D01*
X365100D01*
X370900Y464700D01*
G01X216600Y504230D02*
Y494037D01*
X215270Y492707D01*
Y491100D01*
G01X215658Y486983D02*
X217633D01*
X219800Y489150D01*
Y490550D01*
G01D02*
X219250Y491100D01*
X215270D01*
G01X268448Y520801D02*
Y517196D01*
X280939Y504705D01*
G01X209842Y551969D02*
Y551858D01*
X211300Y550400D01*
X216755D01*
X217741Y549414D01*
Y548177D01*
X218648Y547270D01*
X222314D01*
X225834Y543750D01*
X230994D01*
X240094Y534650D01*
X261700D01*
X268448Y527902D01*
Y520801D01*
G01X209842Y548819D02*
X210158D01*
X211708Y547269D01*
X213798D01*
X214542Y546525D01*
Y545076D01*
X215499Y544119D01*
X217200D01*
X217202Y544120D01*
X220422Y540900D01*
X225953D01*
X227640Y539213D01*
X231287D01*
X235000Y535500D01*
Y531200D01*
X239200Y527000D01*
G01X219485Y582348D02*
X223416D01*
X224098Y581666D01*
G01X216141Y580315D02*
X218174Y582348D01*
X219485D01*
G01X224325Y576816D02*
X221911D01*
X221896Y576801D01*
X219648D01*
G01X216141Y577165D02*
X216505Y576801D01*
X219648D01*
G01X212991Y567718D02*
X214541Y569268D01*
X216784D01*
X217743Y568309D01*
Y567074D01*
X218650Y566167D01*
X220209D01*
X221042Y567000D01*
X223192D01*
G01X228400Y567800D02*
X223992D01*
X223192Y567000D01*
G01X223950Y571900D02*
X222150D01*
X221346Y571096D01*
X218801D01*
G01D02*
X212761D01*
X209841Y574016D01*
G01X219688Y587796D02*
X222354D01*
X224250Y585900D01*
G01X219688Y587796D02*
X216141Y584249D01*
Y583465D01*
G01Y564569D02*
X218158Y562552D01*
X219627D01*
G01X238250Y562600D02*
X235400D01*
X233400Y560600D01*
G01D02*
X229000D01*
X224750Y564850D01*
X222301D01*
X221951Y565200D01*
X218344D01*
X216141Y567403D01*
Y567718D01*
G01X233100Y569900D02*
X233519D01*
X236719Y566700D01*
X238250D01*
G01X219293Y567717D02*
X221476Y569900D01*
X233100D01*
G01X254600Y567700D02*
X256200D01*
X258100Y565800D01*
X260000D01*
X262400Y568200D01*
X262780D01*
X262911Y568331D01*
G01X266800Y571650D02*
X266230D01*
X262911Y568331D01*
G01X266816Y564587D02*
X262848D01*
X262603Y564342D01*
G01X260731Y561264D02*
Y562470D01*
X262603Y564342D01*
G01X233400Y579300D02*
X237343D01*
X238550Y578093D01*
Y575100D01*
G01X233400Y579300D02*
Y576400D01*
X231651Y574651D01*
X217848D01*
X216933Y575566D01*
X214541D01*
X212991Y574016D01*
G01X216141D02*
X216406Y573751D01*
X233659D01*
X234722Y574814D01*
G01X238550Y571000D02*
Y572054D01*
X235790Y574814D01*
X234722D01*
G01X216141Y561419D02*
X216835Y560725D01*
X217734D01*
X218057Y560402D01*
X221119D01*
X223192Y562475D01*
X224359D01*
G01D02*
X225600Y561234D01*
Y559294D01*
X224359Y558053D01*
G01X232500Y529250D02*
X232358Y529392D01*
X228102D01*
G01Y532892D02*
Y534620D01*
X225530Y537192D01*
G01D02*
X223622Y539100D01*
X215380D01*
X212991Y541489D01*
Y542519D01*
G01X232167Y554962D02*
X234912D01*
X238450Y558500D01*
G01X227859Y558053D02*
X229076D01*
X232167Y554962D01*
G01X253700Y531240D02*
X246850D01*
G01X288700Y586900D02*
Y570871D01*
X278017Y560188D01*
Y557888D01*
X273805Y553676D01*
X267519D01*
X264195Y557000D01*
X259306D01*
X259295Y557011D01*
X257761D01*
X257750Y557000D01*
X256800D01*
X254400Y559400D01*
X251820D01*
X250870Y560350D01*
X248581D01*
X247563Y561368D01*
X246145D01*
G01X241750Y562600D02*
X244913D01*
X246145Y561368D01*
G01X246250Y565900D02*
X246700Y565450D01*
Y565060D01*
X249410Y562350D01*
X251699D01*
X252274Y561775D01*
X252284D01*
X252559Y561500D01*
X256150D01*
X258400Y559250D01*
X265804D01*
X269378Y555676D01*
X270912D01*
X270936Y555700D01*
X273000D01*
X275710Y558410D01*
Y560710D01*
X285564Y570564D01*
Y582990D01*
G01X241750Y566700D02*
X245450D01*
X246250Y565900D01*
G01X210900Y536050D02*
X209842Y537108D01*
Y545669D01*
G01X215100Y536050D02*
X210900D01*
G01X242100Y586450D02*
X238100D01*
G01D02*
X234164D01*
X232536Y588078D01*
G01D02*
X230514Y590100D01*
X218672D01*
X216784Y588212D01*
X211441D01*
X209842Y586613D01*
G01X212992Y589764D02*
X213950D01*
X216686Y592500D01*
X220700D01*
X221750Y591450D01*
X233850D01*
X235700Y593300D01*
G01X231892Y546871D02*
X230758D01*
X222600Y555029D01*
G01X216142Y548820D02*
Y548503D01*
X220058Y544587D01*
X221956D01*
G01X216141Y558269D02*
X218526D01*
X219691Y557104D01*
G01X238450Y554400D02*
Y550400D01*
G01D02*
Y546575D01*
X237775Y545900D01*
G01D02*
X237026D01*
X235800Y547126D01*
Y550935D01*
X233923Y552812D01*
X230722D01*
X228634Y554900D01*
X224002D01*
X222200Y556702D01*
Y557700D01*
X221304Y558596D01*
G01X223900Y531200D02*
X222050Y533050D01*
X219200D01*
G01Y536550D02*
X217800Y537950D01*
X213650D01*
X212000Y539600D01*
G01X262000Y586900D02*
X261550Y587350D01*
Y588467D01*
X259650Y590367D01*
Y592233D01*
X264417Y597000D01*
X283294D01*
X295246Y608952D01*
X313883D01*
X323191Y618260D01*
G01X257851Y580080D02*
X259458Y581687D01*
Y584155D01*
X259550Y584247D01*
Y587638D01*
X257650Y589538D01*
Y593062D01*
X263589Y599001D01*
X265245D01*
X265246Y599000D01*
X282465D01*
X294417Y610952D01*
X312983D01*
X330054Y628023D01*
X333600D01*
G01X269359Y587813D02*
X270029D01*
X273490Y584352D01*
G01X269359Y587813D02*
Y585809D01*
X269362D01*
Y583809D01*
G01X261500Y576400D02*
X263259Y578159D01*
X266980D01*
X268721Y579900D01*
X270500D01*
X273490Y582890D01*
Y584352D01*
G01X265700Y580209D02*
X265609Y580300D01*
X261900D01*
X261600Y580000D01*
G01X265862Y583809D02*
X265700Y583647D01*
Y580209D01*
G01X242050Y575100D02*
Y577350D01*
X243767Y579067D01*
X246282D01*
G01X254500Y575070D02*
X253997Y574567D01*
X247000D01*
G01D02*
Y578349D01*
X246282Y579067D01*
G01X242050Y571000D02*
X245224D01*
X246267Y569957D01*
G01X253400Y571400D02*
X252600Y572200D01*
X248510D01*
X246267Y569957D01*
G01X261100Y571600D02*
X258780Y573920D01*
X256179D01*
X254865Y572606D01*
X254606D01*
X253400Y571400D01*
G01X231000Y536584D02*
X229271Y538313D01*
X227267D01*
X225580Y540000D01*
X216424D01*
X214541Y541883D01*
Y543609D01*
X212992Y545158D01*
Y545669D01*
G01X232400Y533200D02*
Y535184D01*
X231000Y536584D01*
G01X243350Y531240D02*
X239260D01*
X238000Y532500D01*
G01X216142Y545669D02*
X217141D01*
X220373Y542437D01*
X226129D01*
X228116Y540450D01*
X232172D01*
X236500Y536122D01*
Y534000D01*
X238000Y532500D01*
G01X270947Y576454D02*
X268104D01*
X266800Y575150D01*
G01X270947Y576454D02*
X272181D01*
X274623Y578896D01*
G01X276839Y582309D02*
X277220Y581928D01*
Y575254D01*
X276329Y574363D01*
Y565041D01*
X272357Y561069D01*
X270836D01*
G01X266816Y561087D02*
X266819Y561084D01*
X270821D01*
X270836Y561069D01*
G01X235772Y542321D02*
X234200Y543893D01*
Y547604D01*
X233036Y548768D01*
Y550942D01*
G01X240150Y539000D02*
X239093D01*
X235772Y542321D01*
G01X240150Y539000D02*
Y541100D01*
X242150Y543100D01*
G01X216000Y626900D02*
X213550Y629350D01*
X212633D01*
X211550Y630433D01*
Y634300D01*
X211750Y634500D01*
G01D02*
Y638400D01*
G01D02*
X211650Y638500D01*
Y642200D01*
G01X222069Y634188D02*
X221488D01*
X218000Y630700D01*
Y630400D01*
G01X222058Y637894D02*
X222069Y637883D01*
Y634188D01*
G01X222042Y642006D02*
X222058Y641990D01*
Y637894D01*
G01X270000Y602400D02*
X268685Y601085D01*
X257052D01*
X256069Y602068D01*
Y609491D01*
X251970Y613590D01*
X249700D01*
G01D02*
X249390Y613900D01*
X236110D01*
X232180Y609970D01*
X229930D01*
X229796Y610104D01*
G01X213161Y623100D02*
Y626700D01*
X209731Y630130D01*
Y644814D01*
X209750Y644833D01*
Y646367D01*
X209729Y646388D01*
Y648079D01*
X211150Y649500D01*
G01D02*
X211058Y649592D01*
Y653294D01*
G01X236350Y633900D02*
X239600D01*
X240900Y635200D01*
G01X232750Y642300D02*
Y641400D01*
X236250Y637900D01*
G01X236350Y633900D02*
Y633650D01*
X234200Y631500D01*
X229500D01*
G01X240900Y635200D02*
Y636900D01*
X239900Y637900D01*
X236250D01*
G01X238100Y610860D02*
X235060D01*
X231100Y606900D01*
X227900D01*
G01X212991Y599212D02*
X212992Y599213D01*
Y602363D01*
G01D02*
X217003D01*
X217560Y602920D01*
X222510D01*
X226490Y606900D01*
X227900D01*
G01X216141Y599212D02*
X217545D01*
X218968Y600635D01*
G01D02*
X221655D01*
X225420Y604400D01*
X229366D01*
X230516Y605550D01*
X231353D01*
X234223Y608420D01*
X240150D01*
X240460Y608110D01*
X243900D01*
X245750Y606260D01*
G01X223150Y597200D02*
Y593200D01*
G01X215519Y594866D02*
X216153Y595500D01*
X220850D01*
X223150Y593200D01*
G01X235700Y593300D02*
X236650Y594250D01*
X242000D01*
G01D02*
X246315D01*
G01X209841Y592913D02*
X209950Y593022D01*
X210852D01*
X214646Y596816D01*
X219807D01*
X221941Y598950D01*
X223130D01*
X226943Y602763D01*
X231066D01*
G01X235360Y602160D02*
Y604069D01*
X235312Y604117D01*
Y606422D01*
G01X231066Y602763D02*
X232902D01*
X233505Y602160D01*
X235360D01*
G01X242000Y656400D02*
X259138Y639262D01*
X259388D01*
X259777Y638873D01*
G01X255200Y680950D02*
X250861Y676611D01*
X249090D01*
G01X259000Y672225D02*
X277842D01*
X283500Y677883D01*
Y678783D01*
X289567Y684850D01*
X327734D01*
X328750Y683834D01*
Y680350D01*
X337600Y671500D01*
Y663901D01*
X334119Y660420D01*
X326300D01*
G01X334200Y241900D02*
X332000Y244100D01*
X315608D01*
X311332Y239824D01*
Y236424D01*
X305782Y230874D01*
G01X335082Y231574D02*
Y241018D01*
X334200Y241900D01*
G01X334998Y255520D02*
X334398D01*
X326778Y247900D01*
X312300D01*
G01D02*
X310739D01*
X307300Y244461D01*
X305454D01*
G01X334998Y259033D02*
X328389Y252424D01*
X325147D01*
G01D02*
X312251D01*
X310727Y250900D01*
X305574D01*
X305373Y251101D01*
G01X313077Y257074D02*
X329618D01*
X335060Y262516D01*
G01X313077Y257074D02*
X309903Y253900D01*
X306851D01*
X306412Y254339D01*
G01X311464Y381211D02*
X317011D01*
X324418Y388618D01*
X326424D01*
X327174Y389368D01*
G01X332407Y393993D02*
X331799D01*
X327174Y389368D01*
G01X303680Y380972D02*
X303919Y381211D01*
X311464D01*
G01X316900Y384100D02*
Y387500D01*
X337000Y407600D01*
Y421498D01*
X332816Y425682D01*
G01X319679Y387121D02*
Y387379D01*
X339269Y406969D01*
Y407733D01*
G01X349182Y377824D02*
X344951D01*
X336282Y386493D01*
G01X344732Y390274D02*
X342900Y392106D01*
Y393097D01*
X342882Y393115D01*
Y394649D01*
X342900Y394667D01*
Y428074D01*
X338800Y432174D01*
Y435100D01*
G01X366950Y464700D02*
Y465650D01*
X364800Y467800D01*
X348600D01*
X330091Y449291D01*
X305370D01*
X305061Y449600D01*
X305031D01*
X288400Y466231D01*
Y466261D01*
X288399Y466262D01*
Y467918D01*
X288400Y467919D01*
Y468631D01*
X282531Y474500D01*
X282403D01*
G01X282400Y470200D02*
X286118Y466482D01*
Y465684D01*
X304202Y447600D01*
X304232D01*
X304541Y447291D01*
X332991D01*
X339900Y454200D01*
G01D02*
X341400Y455700D01*
X362500D01*
X364500Y453700D01*
G01X323759Y435145D02*
X323821D01*
Y435150D01*
X323900Y435071D01*
Y434398D01*
X332616Y425682D01*
X332816D01*
G01X327159Y435201D02*
X327150D01*
Y435200D01*
X327400D01*
X339269Y423331D01*
Y407733D01*
G01X302175Y521026D02*
Y524017D01*
X300476Y525716D01*
Y546907D01*
G01X288309Y566467D02*
X295833D01*
X301463Y560837D01*
Y548749D01*
X303600Y546612D01*
Y528055D01*
X307816Y523839D01*
X318408D01*
X319905Y522342D01*
X328887D01*
X336750Y514479D01*
Y505750D01*
X336600Y505600D01*
Y504500D01*
G01X336800Y499967D02*
X339111Y502278D01*
Y514947D01*
X329672Y524386D01*
X320739D01*
X319128Y525997D01*
X309111D01*
X305600Y529508D01*
Y551000D01*
X303600Y553000D01*
Y561529D01*
X294319Y570810D01*
X291000D01*
G01X332821Y515415D02*
X332985D01*
X334750Y513650D01*
Y512000D01*
G01X331250D02*
Y513450D01*
X328800Y515900D01*
X327600D01*
G01D02*
X323700Y512000D01*
X320650D01*
G01X314150Y509440D02*
Y506000D01*
X314400Y505750D01*
G01X349088Y500296D02*
X348386D01*
X345640Y497550D01*
X343360D01*
X341750Y499160D01*
Y506254D01*
X342850Y507354D01*
Y514037D01*
X330429Y526458D01*
X322293D01*
X316623Y532128D01*
X310292D01*
G01X291800Y576708D02*
X306100Y562408D01*
Y554883D01*
X319680Y541303D01*
X329301D01*
X333800Y536804D01*
Y534830D01*
G01X301653Y572452D02*
X308100Y566005D01*
Y555712D01*
X320421Y543391D01*
X330042D01*
X337550Y535883D01*
Y534619D01*
G01X295824Y578108D02*
X295997D01*
X301653Y572452D01*
G01X323659Y557310D02*
Y560019D01*
X322858Y560820D01*
G01D02*
X321620D01*
X321100Y560300D01*
X311850D01*
X310700Y559150D01*
G01X281610Y590260D02*
X281870Y590000D01*
X285600D01*
X288700Y586900D01*
G01X324200Y565300D02*
X323032Y566468D01*
Y568368D01*
X322800Y568600D01*
Y568609D01*
X322794Y568615D01*
G01D02*
X321104Y570305D01*
X318845D01*
X316150Y573000D01*
G01X281490Y586862D02*
X283538D01*
X285564Y584836D01*
Y582990D01*
G01X315500Y563050D02*
X318892D01*
X319529Y562413D01*
G01X315500Y563050D02*
X311100D01*
X310700Y562650D01*
G01X312650Y573000D02*
Y571550D01*
X315500Y568700D01*
G01X319252Y566509D02*
X317691D01*
X315500Y568700D01*
G01X328771Y549035D02*
Y552597D01*
X340144Y563970D01*
X340538D01*
G01X332808Y547575D02*
X334456Y549223D01*
Y551813D01*
X338200Y555557D01*
Y558000D01*
G01D02*
X340420D01*
X347820Y565400D01*
X348300D01*
G01X325687Y551368D02*
Y550696D01*
X324001Y549010D01*
X322423D01*
G01X320750Y552900D02*
Y550683D01*
X322423Y549010D01*
G01X319430Y557486D02*
X319216Y557700D01*
X315600D01*
G01D02*
X315200Y557300D01*
Y554950D01*
X317250Y552900D01*
G01X316450Y658100D02*
X315536Y657186D01*
Y652822D01*
X316854Y651504D01*
X323518D01*
X324836Y652822D01*
Y652836D01*
X327300Y655300D01*
G01D02*
X327832Y655832D01*
X331718D01*
G01X323191Y618260D02*
X328671Y623740D01*
X341225D01*
X344910Y620055D01*
X355602D01*
X356907Y621360D01*
X360884D01*
X364362Y624838D01*
Y627777D01*
X365228Y628643D01*
Y634045D01*
X370987Y639804D01*
X374087D01*
X377936Y643653D01*
Y644391D01*
X383496Y649951D01*
X385651D01*
X395301Y659601D01*
Y666264D01*
X386372Y675193D01*
Y693028D01*
X381506Y697894D01*
Y701794D01*
X380300Y703000D01*
G01X333600Y628023D02*
X335460D01*
X337743Y625740D01*
X342866D01*
X346156Y622450D01*
X355168D01*
X356078Y623360D01*
X359713D01*
X362362Y626009D01*
Y628606D01*
X363077Y629321D01*
Y634723D01*
X370158Y641804D01*
X373258D01*
X375936Y644482D01*
Y645220D01*
X382667Y651951D01*
X383807D01*
X383808Y651952D01*
X384789D01*
X393301Y660464D01*
Y665435D01*
X383840Y674896D01*
Y688360D01*
X383800Y688400D01*
G01X329100Y650700D02*
X332299D01*
X335862Y654263D01*
Y658627D01*
X340084Y662849D01*
Y663561D01*
X340100Y663577D01*
Y676020D01*
X328770Y687350D01*
X285750D01*
X276100Y677700D01*
G01X319950Y662500D02*
Y658100D01*
G01X308900Y658050D02*
X307150D01*
X303900Y661300D01*
G01X312400Y658050D02*
Y660750D01*
X314250Y662600D01*
G01X316000Y671850D02*
Y669900D01*
X317800Y668100D01*
X326300D01*
G01X338150Y696100D02*
Y697147D01*
X340403Y699400D01*
G01X333338Y696953D02*
Y699522D01*
X335962Y702146D01*
G01X341900Y690350D02*
X341050Y689500D01*
X338033D01*
X333338Y694195D01*
Y696953D01*
G01X341500Y707000D02*
X337316D01*
X335962Y705646D01*
G01X326300Y662980D02*
X320430D01*
X319950Y662500D01*
G01X303900Y661300D02*
X302050Y663150D01*
Y666100D01*
X304450Y668500D01*
X304700D01*
G01X326300Y673220D02*
X331869D01*
X333995Y671094D01*
X334406Y670684D01*
Y667312D01*
X332634Y665540D01*
X326300D01*
G01X315290Y678420D02*
X317260Y676450D01*
X320000D01*
X323230Y673220D01*
X326300D01*
G01X314250Y662600D02*
X317190Y665540D01*
X326300D01*
G01X303800Y681682D02*
X308492D01*
X316224Y673950D01*
X318850D01*
X322140Y670660D01*
X326300D01*
G01X513909Y85849D02*
X512951Y86807D01*
Y97617D01*
X504312Y106256D01*
X477113D01*
X454161Y83304D01*
X431061D01*
X430167Y82410D01*
X397289D01*
X392473Y87226D01*
X390964D01*
G01X388700Y89800D02*
Y86053D01*
X390401Y84352D01*
X393225D01*
X396667Y80910D01*
X430789D01*
X431683Y81804D01*
X454783D01*
X477735Y104756D01*
X503690D01*
X511451Y96995D01*
Y86822D01*
X510408Y85779D01*
G01X344732Y393882D02*
Y428364D01*
X342700Y430396D01*
Y435200D01*
G01X389349Y480100D02*
X395112Y474337D01*
Y367848D01*
X380099Y352835D01*
X369635D01*
X365100Y348300D01*
G01X392800Y677600D02*
X396396D01*
X397306Y676690D01*
Y669210D01*
X398801Y667715D01*
Y658150D01*
X396313Y655662D01*
Y566775D01*
X395450Y565912D01*
Y553744D01*
X397938Y551256D01*
Y505784D01*
X397312Y505158D01*
Y366724D01*
X383030Y352442D01*
G01X364577Y425023D02*
X366253Y423347D01*
Y385991D01*
X358086Y377824D01*
X349182D01*
G01X381106Y441241D02*
X377440Y444907D01*
Y452860D01*
X375900Y454400D01*
X367371D01*
X362571Y459200D01*
X350400D01*
Y459000D01*
G01X374650Y456771D02*
X374279Y456400D01*
X368200D01*
X361700Y462900D01*
X350900D01*
X350400Y462400D01*
G01X372000Y477710D02*
X377540Y483250D01*
Y485411D01*
X379673Y487544D01*
Y488149D01*
X386582Y495058D01*
Y508033D01*
X389037Y510488D01*
Y542251D01*
X386723Y544565D01*
G01X364930Y532400D02*
X364870Y532340D01*
X359466D01*
X358790Y533016D01*
X355924D01*
X354090Y534850D01*
X349065D01*
X343592Y529377D01*
Y526766D01*
X347995Y522363D01*
Y518317D01*
X352888Y513424D01*
Y505112D01*
X355300Y502700D01*
G01X362850Y517340D02*
X361340D01*
X360385Y516385D01*
Y508300D01*
X361018Y507667D01*
Y502318D01*
X357700Y499000D01*
G01X369350Y522460D02*
X371600Y524710D01*
Y531750D01*
X368390Y534960D01*
X364930D01*
G01X369350Y522460D02*
X372399D01*
X373699Y521160D01*
G01X351900Y532350D02*
X350101D01*
X348650Y530899D01*
Y525896D01*
X350495Y524051D01*
Y519353D01*
X352111Y517737D01*
G01D02*
X353648Y516200D01*
X356000D01*
X357885Y514314D01*
Y504415D01*
X359100Y503200D01*
G01X369350Y519900D02*
X371400D01*
X374388Y516912D01*
X374800D01*
G01X373383Y511449D02*
Y515495D01*
X374800Y516912D01*
G01X364014Y593996D02*
X363975Y593957D01*
Y593717D01*
X360648Y590390D01*
X360300D01*
G01X356480D02*
X360300D01*
G01X346303Y591947D02*
X348636Y589614D01*
X352480D01*
G01X345244Y583810D02*
X344066Y582632D01*
Y579700D01*
G01D02*
Y575842D01*
X344067Y575841D01*
G01D02*
X343520Y575294D01*
Y572850D01*
X342440Y571770D01*
G01X365400Y572650D02*
X369500D01*
G01X365400D02*
X358550D01*
X358100Y572200D01*
G01X361900Y570800D02*
X361400Y570300D01*
X358600D01*
X358100Y570800D01*
Y572200D01*
G01X388870Y711260D02*
X390540D01*
X395500Y706300D01*
Y696390D01*
X393460Y694350D01*
X391733D01*
X389908Y692525D01*
Y676478D01*
X390794Y675592D01*
X394808D01*
X395602Y674798D01*
Y668792D01*
X397301Y667093D01*
Y658772D01*
X394813Y656284D01*
Y584974D01*
X391993Y582154D01*
G01X362300Y555200D02*
X361791D01*
X356300Y549709D01*
Y549100D01*
G01X356046Y545220D02*
Y548846D01*
X356300Y549100D01*
G01X367050Y540600D02*
Y546930D01*
X368373Y548253D01*
Y553334D01*
X369039Y554000D01*
G01X364930Y534960D02*
Y538480D01*
X367050Y540600D01*
G01X369039Y554000D02*
Y557740D01*
X367316Y559463D01*
X366350D01*
G01X358430Y529840D02*
X357754Y530516D01*
X354888D01*
X353054Y532350D01*
X351900D01*
G01X343840Y566440D02*
X341370Y563970D01*
X340538D01*
G01X360300Y561850D02*
Y566000D01*
X360500Y566200D01*
G01X366270Y563400D02*
X365816Y563854D01*
X364423D01*
X362077Y566200D01*
X360500D01*
G01X373850Y563338D02*
X366332D01*
X366270Y563400D01*
G01X400060Y554743D02*
X396950Y557853D01*
Y564310D01*
X397813Y565173D01*
Y655040D01*
X400302Y657529D01*
Y661706D01*
X400301Y661707D01*
Y667924D01*
X402485Y670108D01*
Y685143D01*
X396848Y690780D01*
X395399D01*
X393679Y692500D01*
X392500D01*
G01X377635Y616107D02*
Y618165D01*
X379166Y619696D01*
Y620503D01*
G01X377635Y616107D02*
X381951D01*
X381967Y616123D01*
G01X359929Y626617D02*
Y629002D01*
X361227Y630300D01*
G01X380000Y598350D02*
Y597300D01*
X377700Y595000D01*
G01X383199Y623168D02*
X383057Y623310D01*
Y625037D01*
X379014Y629080D01*
X378814D01*
G01X378800Y624850D02*
X378814Y624864D01*
Y629080D01*
G01X378800Y624850D02*
X375716D01*
X374534Y626032D01*
G01X384365Y605713D02*
Y606828D01*
X382438Y608755D01*
G01X343200Y667600D02*
X346260Y670660D01*
X348500D01*
G01Y662980D02*
X354400D01*
X355620Y664200D01*
X362450D01*
G01X342600Y682800D02*
Y686050D01*
X344050Y687500D01*
G01X342600Y682800D02*
X345188Y680212D01*
Y678469D01*
X344750Y678031D01*
Y673850D01*
X345380Y673220D01*
X348500D01*
G01X389999Y664697D02*
Y662576D01*
X388017Y660594D01*
G01X365950Y664200D02*
X372501D01*
X376107Y660594D01*
X388017D01*
G01X367700Y685450D02*
X366050Y683800D01*
X362900D01*
G01D02*
X361400D01*
X358710Y686490D01*
X348560D01*
X347550Y687500D01*
G01X388870Y711260D02*
X387240D01*
X382649Y715851D01*
X363061D01*
X361070Y713860D01*
Y707160D01*
G01X360970Y694560D02*
X357920Y697610D01*
Y705120D01*
X359960Y707160D01*
X361070D01*
G01X357050Y683400D02*
Y676450D01*
X358800Y674700D01*
X376000D01*
X382308Y668392D01*
Y665022D01*
G01X353550Y683400D02*
X350100D01*
X349190Y682490D01*
G01X348500Y675780D02*
X351750D01*
X353300Y674230D01*
Y669799D01*
X351601Y668100D01*
X348500D01*
G01X349190Y682490D02*
X348500Y681800D01*
Y675780D01*
G01X375707Y695203D02*
X375547D01*
X372350Y698400D01*
G01X375500Y704250D02*
Y701572D01*
X377199Y699873D01*
G01X382370Y706140D02*
X377390D01*
X375500Y704250D01*
G01X377199Y699873D02*
X379207Y697865D01*
Y695203D01*
G01X345654Y700065D02*
X349212Y696507D01*
Y694609D01*
X351821Y692000D01*
X354470D01*
G01X345654Y700065D02*
X342619Y703100D01*
X340300D01*
G01X345654Y696565D02*
Y693432D01*
X347010Y692076D01*
G01X345654Y696565D02*
X345619Y696600D01*
X342150D01*
X341650Y696100D01*
G01X347010Y692076D02*
X349646Y689440D01*
X354470D01*
G01X354570Y704600D02*
X352650D01*
X347500Y709750D01*
G01D02*
Y713600D01*
X346600Y714500D01*
G01X354570Y702040D02*
X351710D01*
X347500Y706250D01*
G01X341500Y707000D02*
X346750D01*
X347500Y706250D01*
G01X375500Y707750D02*
X376450Y708700D01*
X382370D01*
G01X380387Y685261D02*
Y686281D01*
X370476Y696191D01*
Y705577D01*
X372649Y707750D01*
X375500D01*
G01X378595Y664960D02*
Y667253D01*
X373948Y671900D01*
X370550D01*
G01X348500Y665540D02*
X353424D01*
X354584Y666700D01*
X356200D01*
X361400Y671900D01*
X362700D01*
G01X367050D02*
X362700D01*
G01X456400Y54350D02*
Y34650D01*
X457450Y33600D01*
G01X458500Y27000D02*
X457450Y28050D01*
Y33600D01*
G01X467500Y25500D02*
Y21367D01*
X467300Y21167D01*
Y20000D01*
G01X467500Y25500D02*
X460000D01*
X458500Y27000D01*
G01X445900Y37700D02*
Y40151D01*
X444051Y42000D01*
X443500D01*
G01X450454Y38147D02*
X450007Y37700D01*
X445900D01*
G01X443500Y42000D02*
X442849D01*
X441450Y40601D01*
Y37800D01*
G01X448520Y49979D02*
X448506Y49965D01*
X442332D01*
X439288Y46921D01*
G01X437950Y37800D02*
Y45583D01*
X439288Y46921D01*
G01X430800Y22200D02*
Y25824D01*
X430751Y25873D01*
Y51068D01*
X426210Y55609D01*
Y64878D01*
X419662Y71426D01*
G01X433600Y19900D02*
X433400Y20100D01*
Y26053D01*
X432751Y26702D01*
Y51897D01*
X428210Y56438D01*
Y66751D01*
X423340Y71621D01*
G01X453950Y33600D02*
X452455Y35095D01*
Y48845D01*
X449100Y52200D01*
X440683D01*
X430649Y62234D01*
Y66965D01*
X436154Y72470D01*
G01X456400Y57850D02*
Y61850D01*
X456450Y61900D01*
G01D02*
Y64750D01*
X457700Y66000D01*
X459700D01*
G01D02*
X462350D01*
X466550Y61800D01*
G01D02*
X475300D01*
X478200Y58900D01*
X479850D01*
G01X479147Y102165D02*
X477431Y100449D01*
Y95378D01*
X459333Y77280D01*
X440964D01*
X436154Y72470D01*
G01X500411Y55315D02*
X497100D01*
X496000Y56415D01*
G01X500411Y55315D02*
X502453D01*
X503814Y56676D01*
G01X496000Y56415D02*
Y60600D01*
X495500Y61100D01*
Y61115D01*
G01D02*
X491081D01*
X490653Y60687D01*
G01X507250Y65000D02*
X503760D01*
X502930Y64170D01*
G01X507895Y60597D02*
X505313D01*
X502930Y62980D01*
Y64170D01*
G01X512290Y57723D02*
X510769D01*
X507895Y60597D01*
G01X512290Y57723D02*
X515323D01*
X515500Y57900D01*
G01X486568Y38006D02*
Y35473D01*
X487586Y34455D01*
X489744D01*
G01X489691Y42317D02*
X489750Y42258D01*
Y38500D01*
G01X489691Y42317D02*
X486731D01*
X486114Y41700D01*
G01X485674Y32924D02*
X485600D01*
Y32850D01*
X488002Y30448D01*
X489729D01*
G01X477943Y34165D02*
X484433D01*
X485674Y32924D01*
G01X481800Y71200D02*
X481100Y70500D01*
Y67676D01*
X481093Y67669D01*
G01X479850Y62900D02*
X476825D01*
X474050Y65675D01*
G01X481093Y67669D02*
X480750Y67326D01*
Y63800D01*
X479850Y62900D01*
G01X573750Y67500D02*
X571542D01*
X571492Y67450D01*
X570476D01*
X569300Y66274D01*
G01X573750Y64940D02*
X573234Y64424D01*
X568193D01*
X560427Y72190D01*
X555739D01*
X553540Y69991D01*
Y69940D01*
X551250D01*
G01X544814Y62686D02*
X542500Y65000D01*
Y70500D01*
X544500Y72500D01*
X551250D01*
G01X544814Y62686D02*
X545600Y61900D01*
X549550D01*
G01X551250Y69940D02*
X546140D01*
X545200Y69000D01*
G01X547100Y79900D02*
Y79922D01*
X549072Y77950D01*
X556450D01*
X557750Y76650D01*
Y75060D01*
G01X580250Y70060D02*
Y72650D01*
X578400Y74500D01*
G01X598941Y368050D02*
X596459Y365568D01*
Y356633D01*
X598964Y354128D01*
G01X593064Y400910D02*
X612476D01*
X629581Y383805D01*
X638360D01*
G01X593229Y397308D02*
X612227D01*
X627744Y381791D01*
X640192D01*
X642270Y383869D01*
G01X653520Y211250D02*
Y205253D01*
X657563Y201210D01*
X660556D01*
X669496Y192270D01*
X679819D01*
X683819Y196270D01*
X690342D01*
X690825Y196753D01*
Y197461D01*
X689497Y198789D01*
Y199497D01*
X690204Y200204D01*
X690912D01*
X692240Y198876D01*
X692948D01*
X695768Y201696D01*
Y202404D01*
X693065Y205107D01*
Y205815D01*
X693772Y206522D01*
X694480D01*
X697183Y203819D01*
X697891D01*
X698598Y204526D01*
Y205234D01*
X693270Y210562D01*
Y211270D01*
X693977Y211977D01*
X694685D01*
X701252Y205410D01*
X701960D01*
X702667Y206117D01*
Y206825D01*
X698725Y210767D01*
Y211475D01*
X699432Y212182D01*
X700140D01*
X702843Y209479D01*
X703551D01*
X704550Y210478D01*
Y212534D01*
X705816Y213800D01*
X707266D01*
X708216Y212850D01*
X725055D01*
X727560Y215355D01*
G01X716116Y207469D02*
X717027Y208380D01*
Y209924D01*
X716451Y210500D01*
X713100D01*
X711000Y208400D01*
X710292D01*
X708250Y210442D01*
X707542D01*
X706835Y209735D01*
Y209027D01*
X708877Y206985D01*
Y206277D01*
X692870Y190270D01*
X685648D01*
X685148Y190770D01*
Y191770D01*
X685648Y192270D01*
X692000D01*
X701325Y201595D01*
Y202525D01*
X700825Y203025D01*
X699926D01*
X691171Y194270D01*
X684648D01*
X680648Y190270D01*
X668667D01*
X659727Y199210D01*
X656734D01*
X655394Y200550D01*
X655000D01*
X649585Y205965D01*
Y211250D01*
G01X631870D02*
Y202980D01*
X641750Y193100D01*
X657350D01*
X666180Y184270D01*
X698958D01*
X717439Y202751D01*
X726215D01*
X726304Y202662D01*
X733012D01*
X740400Y210050D01*
X743467D01*
X746457Y213040D01*
Y215355D01*
G01X641710Y211250D02*
Y205263D01*
X641210Y204763D01*
X640100D01*
X639600Y204263D01*
Y203263D01*
X640100Y202763D01*
X641210D01*
X641710Y202263D01*
Y199173D01*
X643783Y197100D01*
X651062D01*
X651562Y197600D01*
Y198800D01*
X652062Y199300D01*
X653062D01*
X653562Y198800D01*
Y197600D01*
X654062Y197100D01*
X659008D01*
X667838Y188270D01*
X696712D01*
X700325Y191883D01*
Y192591D01*
X699787Y193129D01*
Y193837D01*
X700494Y194544D01*
X701202D01*
X701740Y194006D01*
X702448D01*
X703155Y194713D01*
Y195421D01*
X702617Y195959D01*
Y196667D01*
X703324Y197374D01*
X704032D01*
X704570Y196836D01*
X705278D01*
X705985Y197543D01*
Y198251D01*
X705447Y198789D01*
Y199497D01*
X706154Y200204D01*
X706862D01*
X707400Y199666D01*
X708108D01*
X709513Y201071D01*
X710171D01*
X713653Y204553D01*
X715295Y204551D01*
X718726D01*
X721037Y206862D01*
X728045D01*
X728157Y206750D01*
X731095D01*
X731207Y206862D01*
X731761D01*
X737029Y212130D01*
Y215337D01*
G01X637775Y211250D02*
Y205309D01*
X637275Y204809D01*
X635550D01*
X635050Y204309D01*
Y203309D01*
X635550Y202809D01*
X637275D01*
X637775Y202309D01*
Y200025D01*
X642700Y195100D01*
X658179D01*
X667009Y186270D01*
X697869D01*
X715250Y203651D01*
X720413D01*
X722724Y205962D01*
X727672D01*
X727784Y205850D01*
X731468D01*
X731580Y205962D01*
X732362D01*
X739542Y213142D01*
X741057D01*
X743279Y215364D01*
G01X657460Y211250D02*
Y204142D01*
X658392Y203210D01*
X661385D01*
X670325Y194270D01*
X678720D01*
X680100Y195650D01*
Y204200D01*
X682652Y206752D01*
X683360D01*
X687252Y202860D01*
X687960D01*
X688667Y203567D01*
Y204275D01*
X684775Y208167D01*
Y208875D01*
X685482Y209582D01*
X686190D01*
X687982Y207790D01*
X688690D01*
X689397Y208497D01*
Y209205D01*
X687605Y210997D01*
Y211705D01*
X690757Y214857D01*
X691465D01*
X692232Y214090D01*
X692940D01*
X693647Y214797D01*
Y215505D01*
X692880Y216272D01*
Y216980D01*
X693650Y217750D01*
X699644D01*
X700144Y217250D01*
Y215600D01*
X700644Y215100D01*
X701644D01*
X702144Y215600D01*
Y217250D01*
X702644Y217750D01*
X703644D01*
X704144Y217250D01*
Y215600D01*
X704644Y215100D01*
X705644D01*
X706144Y215600D01*
Y217250D01*
X706644Y217750D01*
X711215D01*
X711715Y217250D01*
Y214650D01*
X712215Y214150D01*
X713215D01*
X713715Y214650D01*
Y217250D01*
X714215Y217750D01*
X715215D01*
X715715Y217250D01*
Y214650D01*
X716215Y214150D01*
X717215D01*
X717715Y214650D01*
Y217250D01*
X718215Y217750D01*
X719215D01*
X719715Y217250D01*
Y214650D01*
X720215Y214150D01*
X721215D01*
X721715Y214650D01*
Y217250D01*
X722215Y217750D01*
X723909D01*
X724410Y217249D01*
Y215355D01*
G01X629500Y194250D02*
X627930Y195820D01*
Y198500D01*
G01X634000Y194250D02*
X629500D01*
G01X627930Y198500D02*
Y211250D01*
G01X637775Y286950D02*
Y275264D01*
X637740Y275229D01*
Y270173D01*
X637240Y269673D01*
X635100D01*
X634600Y269173D01*
Y268173D01*
X635100Y267673D01*
X637240D01*
X637740Y267173D01*
Y266173D01*
X637240Y265673D01*
X634600D01*
X634150Y265223D01*
Y264123D01*
X634600Y263673D01*
X637240D01*
X637740Y263173D01*
Y262173D01*
X637240Y261673D01*
X634700D01*
X634400Y261373D01*
Y259973D01*
X634700Y259673D01*
X637240D01*
X637740Y259173D01*
Y258173D01*
X637240Y257673D01*
X634450D01*
X634150Y257373D01*
Y255973D01*
X634450Y255673D01*
X637240D01*
X637740Y255173D01*
Y252682D01*
X637158Y252100D01*
X634450D01*
G01X631550Y249850D02*
X632150Y250450D01*
Y269800D01*
X635740Y273390D01*
Y275229D01*
X635805Y275294D01*
Y286950D01*
G01X625926Y247530D02*
X629960Y251564D01*
Y274639D01*
X631870Y276549D01*
Y286950D01*
G01X627200Y253550D02*
X627350D01*
X627250Y253650D01*
Y253872D01*
X627960Y254582D01*
Y276560D01*
X628050Y276650D01*
X628262D01*
X629900Y278288D01*
Y286950D01*
G01X625250Y264250D02*
X625960Y264960D01*
Y277389D01*
X627221Y278650D01*
X627460D01*
X627960Y279150D01*
Y281209D01*
X627930Y281239D01*
Y286950D01*
G01X625550Y244150D02*
X625300D01*
X622600Y246850D01*
Y249300D01*
X622100Y249800D01*
X620050D01*
X619550Y250300D01*
Y251300D01*
X620050Y251800D01*
X624300D01*
X624800Y252300D01*
Y253300D01*
X624300Y253800D01*
X620050D01*
X619550Y254300D01*
Y255300D01*
X620050Y255800D01*
X622100D01*
X622600Y256300D01*
Y264800D01*
X623960Y266160D01*
Y278218D01*
X625960Y280218D01*
Y286950D01*
G01Y211250D02*
Y218330D01*
X625460Y218830D01*
X620900D01*
X620400Y219330D01*
Y220330D01*
X620900Y220830D01*
X630400D01*
X630900Y221330D01*
Y222330D01*
X630400Y222830D01*
X621150D01*
X620650Y223330D01*
Y224330D01*
X621150Y224830D01*
X630650D01*
X631150Y225330D01*
Y226330D01*
X630650Y226830D01*
X626460D01*
X625960Y227330D01*
Y231940D01*
X623100Y234800D01*
Y238300D01*
X625550Y240750D01*
G01X645516Y225334D02*
Y236116D01*
X671395Y261995D01*
Y277929D01*
X671240Y278084D01*
Y286950D01*
G01X623995D02*
Y281082D01*
X621960Y279047D01*
Y268260D01*
X620550Y266850D01*
Y258250D01*
X620750Y258050D01*
G01X642547Y226992D02*
Y236848D01*
X669395Y263696D01*
Y277929D01*
X669330Y277994D01*
Y278754D01*
X669285Y278800D01*
X669270Y278815D01*
Y286950D01*
G01X632958Y231000D02*
X667395Y265437D01*
Y277929D01*
X667330Y277994D01*
Y278755D01*
X667300Y278785D01*
Y286950D01*
G01X633109Y234397D02*
X665395Y266683D01*
Y277929D01*
X665330Y277994D01*
Y286950D01*
G01X632900Y238000D02*
X663365Y268465D01*
Y268836D01*
X663395Y268866D01*
Y277929D01*
X663365Y277959D01*
Y286950D01*
G01X628300Y230550D02*
X628150Y230700D01*
Y236450D01*
X661395Y269695D01*
Y286950D01*
G01X625700Y235750D02*
Y237813D01*
X659395Y271508D01*
Y277929D01*
X659425Y277959D01*
Y286950D01*
G01X639740D02*
Y274627D01*
X640240Y274127D01*
X644950D01*
X645450Y273627D01*
Y272627D01*
X644950Y272127D01*
X640240D01*
X639740Y271627D01*
Y270627D01*
X640240Y270127D01*
X648300D01*
X648800Y269627D01*
Y268627D01*
X648300Y268127D01*
X640240D01*
X639740Y267627D01*
Y266627D01*
X640240Y266127D01*
X643050D01*
X643550Y265627D01*
Y264627D01*
X643050Y264127D01*
X640240D01*
X639740Y263627D01*
Y260510D01*
X640141Y260109D01*
Y259859D01*
G01X718110Y234252D02*
X705608Y221750D01*
X699847D01*
X699347Y221250D01*
Y220550D01*
X698847Y220050D01*
X697847D01*
X697347Y220550D01*
Y223700D01*
X696847Y224200D01*
X695847D01*
X695347Y223700D01*
Y220250D01*
X694847Y219750D01*
X693847D01*
X693347Y220250D01*
Y222900D01*
X692847Y223400D01*
X691847D01*
X691347Y222900D01*
Y218400D01*
X690847Y217900D01*
X689847D01*
X689347Y218400D01*
Y222100D01*
X688847Y222600D01*
X687847D01*
X687347Y222100D01*
Y214500D01*
X686847Y214000D01*
X685847D01*
X685347Y214500D01*
Y222050D01*
X684847Y222550D01*
X683847D01*
X683347Y222050D01*
Y211150D01*
X682847Y210650D01*
X681847D01*
X681347Y211150D01*
Y221500D01*
X680847Y222000D01*
X679847D01*
X679347Y221500D01*
Y219050D01*
X678847Y218550D01*
X677847D01*
X677347Y219050D01*
Y221250D01*
X676847Y221750D01*
X675847D01*
X675347Y221250D01*
Y218400D01*
X674847Y217900D01*
X673847D01*
X673347Y218400D01*
Y221100D01*
X672847Y221600D01*
X671847D01*
X671347Y221100D01*
Y219546D01*
X670201Y218400D01*
X665722D01*
X663365Y216043D01*
Y211250D01*
G01X709679Y239164D02*
X708059Y237544D01*
Y236530D01*
X702329Y230800D01*
X697750D01*
X697074Y230124D01*
Y226850D01*
X696574Y226350D01*
X695574D01*
X695074Y226850D01*
Y230600D01*
X694574Y231100D01*
X693574D01*
X693074Y230600D01*
Y225900D01*
X692574Y225400D01*
X691574D01*
X691074Y225900D01*
Y227150D01*
X690574Y227650D01*
X689574D01*
X689074Y227150D01*
Y225150D01*
X688574Y224650D01*
X687574D01*
X687074Y225150D01*
Y230600D01*
X686574Y231100D01*
X685574D01*
X685074Y230600D01*
Y225000D01*
X684624Y224550D01*
X683524D01*
X683074Y225000D01*
Y230600D01*
X682574Y231100D01*
X681574D01*
X681074Y230600D01*
Y224600D01*
X680574Y224100D01*
X679574D01*
X679074Y224600D01*
Y230600D01*
X678574Y231100D01*
X677574D01*
X677074Y230600D01*
Y224550D01*
X676574Y224050D01*
X675574D01*
X675074Y224550D01*
Y230600D01*
X674574Y231100D01*
X673574D01*
X673074Y230600D01*
Y224424D01*
X672500Y223850D01*
X669743D01*
X669243Y223350D01*
Y221250D01*
X668743Y220750D01*
X667743D01*
X667243Y221250D01*
Y223350D01*
X666743Y223850D01*
X666151D01*
X659425Y217124D01*
Y211250D01*
G01X643680D02*
Y218951D01*
X670735Y246006D01*
Y246713D01*
X669453Y247995D01*
X668745D01*
X659953Y239203D01*
X659245Y239204D01*
X658179Y240272D01*
X658180Y240980D01*
X668700Y251500D01*
X697948D01*
X698768Y250680D01*
Y250679D01*
X700733Y248714D01*
X703885D01*
X706349Y246250D01*
X714745D01*
X715736Y245259D01*
X716582D01*
G01X640400Y217600D02*
X639740Y216940D01*
Y211250D01*
G01X636491Y217592D02*
X635805Y216906D01*
Y211250D01*
G01X718111Y240550D02*
X716250D01*
X715000Y241800D01*
X709954D01*
X706833Y238679D01*
X705229D01*
X703700Y237150D01*
X674350D01*
X673850Y236650D01*
Y235650D01*
X674350Y235150D01*
X702200D01*
X702700Y234650D01*
Y233650D01*
X702200Y233150D01*
X672304D01*
X655490Y216336D01*
Y211250D01*
G01X651555D02*
Y217287D01*
X656252Y221984D01*
Y222692D01*
X655201Y223743D01*
Y224451D01*
X655908Y225158D01*
X656616D01*
X657667Y224107D01*
X658375D01*
X659082Y224814D01*
Y225522D01*
X658031Y226573D01*
Y227281D01*
X658738Y227988D01*
X659446D01*
X660497Y226937D01*
X661205D01*
X661912Y227644D01*
Y228352D01*
X660861Y229403D01*
Y230111D01*
X661568Y230818D01*
X662276D01*
X663327Y229767D01*
X664035D01*
X664742Y230474D01*
Y231182D01*
X663691Y232233D01*
Y232941D01*
X664398Y233648D01*
X665106D01*
X666157Y232597D01*
X666865D01*
X667572Y233304D01*
Y234012D01*
X666521Y235063D01*
Y235771D01*
X667228Y236478D01*
X667936D01*
X668987Y235427D01*
X669695D01*
X670402Y236134D01*
Y236842D01*
X669351Y237893D01*
Y238601D01*
X670058Y239308D01*
X670766D01*
X671817Y238257D01*
X672525D01*
X673559Y239291D01*
X690987D01*
X691487Y239791D01*
Y240791D01*
X690987Y241291D01*
X675400D01*
X674900Y241791D01*
Y242791D01*
X675400Y243291D01*
X692987D01*
X693487Y242791D01*
Y239791D01*
X693987Y239291D01*
X701241D01*
X705650Y243700D01*
X711812D01*
G01X714961D02*
X713311Y245350D01*
X701101D01*
X697101Y249350D01*
X673850D01*
X673350Y248850D01*
Y247850D01*
X673850Y247350D01*
X695900D01*
X696400Y246850D01*
Y245850D01*
X695900Y245350D01*
X673151D01*
X645645Y217844D01*
Y211250D01*
G01X633092Y217496D02*
X633835Y216753D01*
Y211250D01*
G01X659500Y205300D02*
X661395Y207195D01*
Y211250D01*
G01X670200Y203350D02*
X669810D01*
X668360Y201900D01*
X665500D01*
G01X662900Y205300D02*
X665330Y207730D01*
Y211250D01*
G01X645400Y264050D02*
X649000D01*
X650850Y265900D01*
Y274825D01*
X645645Y280030D01*
Y286950D01*
G01X656665Y298416D02*
X657603Y297478D01*
Y294530D01*
G01X651555Y286950D02*
Y289953D01*
X654779Y293177D01*
X656250D01*
X657603Y294530D01*
G01X633400Y274600D02*
Y274889D01*
X633835Y275324D01*
Y286950D01*
G01X657500Y281500D02*
X657460Y281540D01*
Y286950D01*
G01X652850Y269600D02*
X654021D01*
X654521Y270100D01*
Y281923D01*
X655490Y282892D01*
Y286950D01*
G01X641710D02*
Y277040D01*
X642300Y276450D01*
G01X643680Y286950D02*
Y279070D01*
X647450Y275300D01*
Y274455D01*
X648405Y273500D01*
X649000D01*
G01X652100Y279300D02*
Y279650D01*
X650493Y281257D01*
Y281963D01*
X649585Y282871D01*
Y286950D01*
G01X648000Y281300D02*
X647615Y281685D01*
Y286950D01*
G01X645645D02*
Y290280D01*
X646365Y291000D01*
X649310D01*
X652465Y294155D01*
Y294735D01*
G01D02*
Y298516D01*
G01X654600Y367600D02*
X654540Y367660D01*
X626988D01*
G01D02*
X624627Y370021D01*
X614821D01*
X613236Y368436D01*
Y367271D01*
G01X604059Y368050D02*
X612457D01*
X613236Y367271D01*
G01X637353Y379591D02*
X655299D01*
X664908Y389200D01*
X712200D01*
X718900Y395900D01*
Y410900D01*
X720900Y412900D01*
G01X677770Y196410D02*
Y200630D01*
X671240Y207160D01*
Y211250D01*
G01X730900Y194750D02*
Y195385D01*
X725466Y200819D01*
G01X718121Y256326D02*
X714067D01*
X712429Y257964D01*
G01X715775Y261939D02*
X715715Y261999D01*
X711102D01*
G01X715775Y261939D02*
Y261310D01*
X712429Y257964D01*
G01X718089Y246834D02*
X717773Y247150D01*
X711900D01*
X709650Y249400D01*
G01X713823Y253883D02*
Y250068D01*
X714226Y249665D01*
G01X718089Y249984D02*
X717770Y249665D01*
X714226D01*
G01X718810Y264077D02*
X705366D01*
X702343Y267100D01*
X701654D01*
G01X710716Y235827D02*
X711127D01*
X714100Y238800D01*
G01X714945Y234230D02*
X713515Y232800D01*
X711000D01*
G01X733859Y215355D02*
X733345D01*
X729930Y211940D01*
G01X670200Y203350D02*
Y205311D01*
X669270Y206241D01*
Y211250D01*
G01X723210Y209850D02*
X728350D01*
X729800Y208400D01*
G01X709600Y299400D02*
X706796Y296596D01*
Y295829D01*
G01X720530Y312210D02*
X723802D01*
X726895Y309117D01*
G01X715200Y300000D02*
X711799Y303401D01*
Y304234D01*
G01X713339Y306954D02*
X711893Y308400D01*
X709500D01*
G01X724063Y306305D02*
X726505D01*
X728800Y308600D01*
Y311100D01*
X726800Y313100D01*
Y313113D01*
G01X693200Y279550D02*
X698039Y284389D01*
Y285854D01*
G01X707834Y293060D02*
X706952D01*
X702109Y297903D01*
G01X707079Y286964D02*
X706815Y286700D01*
X702400D01*
G01X700700Y305100D02*
X704079Y301721D01*
Y300964D01*
G01X716060Y309320D02*
X717280D01*
X719200Y307400D01*
G01X706600Y303800D02*
Y299485D01*
X705579Y298464D01*
G01X695508Y288964D02*
X695505Y288967D01*
X691774D01*
G01X710679Y267894D02*
X713694D01*
X714400Y268600D01*
G01X721230Y284653D02*
Y291981D01*
X718260Y294951D01*
G01X711322Y294199D02*
X714557Y290964D01*
X718099D01*
G01X706997Y283155D02*
X709056Y285214D01*
X710329D01*
G01X711029Y279114D02*
X715766D01*
X718117Y281465D01*
G01X718080Y284653D02*
X717562Y284135D01*
X713789D01*
G01X697960Y292400D02*
X701672D01*
X701708Y292364D01*
G01X706277Y279162D02*
Y278690D01*
X703526Y275939D01*
G01X714519Y275114D02*
X717751Y278346D01*
X718072D01*
G01X708409Y276771D02*
X707604Y275966D01*
Y272070D01*
G01X736952Y311391D02*
Y308049D01*
X730708Y301805D01*
Y297243D01*
G01X714619Y303884D02*
X715035Y304300D01*
X718600D01*
G01X718072Y265748D02*
X718008D01*
X717987Y265727D01*
X708773D01*
X705300Y269200D01*
X695697D01*
G01D02*
X689050D01*
G01Y265100D02*
X691050Y267100D01*
X701654D01*
G01X732230Y307819D02*
X732116D01*
X727996Y303699D01*
G01X727558Y297243D02*
Y303261D01*
X727996Y303699D01*
G01X724409Y297243D02*
X722961Y298691D01*
Y300982D01*
G01X700323Y283078D02*
Y280147D01*
X698773Y278597D01*
G01X733859Y284646D02*
Y285060D01*
X732859Y286060D01*
X730450D01*
X728580Y287930D01*
G01X695200Y301800D02*
Y306600D01*
X695300Y306700D01*
G01X695200Y301800D02*
Y301770D01*
X695700Y301270D01*
X695701D01*
X707266Y289705D01*
X716208D01*
X718099Y287814D01*
G01X708300Y452750D02*
Y457206D01*
X711368Y460274D01*
Y468668D01*
X715391Y472691D01*
Y479109D01*
G01X720900Y434172D02*
Y440540D01*
X709290Y452150D01*
X708900D01*
X708300Y452750D01*
G01X720900Y434172D02*
Y412900D01*
G01X747200Y611900D02*
X747140Y611840D01*
X722122D01*
G01X744960Y197430D02*
X743100Y199290D01*
X738350D01*
X738160Y199480D01*
G01X821250Y244200D02*
X820080Y245370D01*
X811866D01*
X807936Y249300D01*
X803188D01*
X800866Y251622D01*
X798552D01*
X794670Y247740D01*
X791140D01*
G01D02*
Y247439D01*
X787402Y243701D01*
G01X793700Y256262D02*
X795362Y254600D01*
X800650D01*
X803550Y251700D01*
X808315D01*
X810279Y253664D01*
X812178D01*
G01X752700Y214100D02*
X752759Y214159D01*
Y218499D01*
G01X755909Y218514D02*
Y210344D01*
X753479Y207914D01*
G01X787770Y254660D02*
X787850Y254580D01*
X789120D01*
X790550Y253150D01*
G01X786440Y249880D02*
X787700Y251220D01*
X787770Y251290D01*
Y254660D01*
G01X798770Y259500D02*
Y257511D01*
X799972Y256309D01*
G01X820050Y248200D02*
X818929Y247079D01*
X811739D01*
X808378Y250440D01*
X803321D01*
X800541Y253220D01*
X793592D01*
X790523Y256289D01*
G01X797500Y226000D02*
Y226500D01*
X798679Y227679D01*
Y236833D01*
X800021Y238175D01*
Y243717D01*
G01X802100Y225950D02*
X797550D01*
X797500Y226000D01*
G01X741294Y208274D02*
X741183Y208163D01*
Y203179D01*
X742252Y202110D01*
X744482D01*
G01X745650Y208500D02*
Y203278D01*
X744482Y202110D01*
G01X741100Y307400D02*
X741500Y307000D01*
Y298586D01*
X740157Y297243D01*
G01X739100Y302126D02*
Y299336D01*
X737008Y297244D01*
G01X733892Y297246D02*
X733696Y297442D01*
Y300991D01*
G01X744768Y300864D02*
X743306Y299402D01*
Y297243D01*
G01X748100Y281300D02*
X746623Y282777D01*
X745177D01*
X743308Y284646D01*
G01X746457D02*
Y286457D01*
X748000Y288000D01*
G01X828781Y231061D02*
X824787D01*
X824148Y231700D01*
X816900D01*
G01X828800Y235850D02*
Y231080D01*
X828781Y231061D01*
G01X812178Y253664D02*
X812630Y253212D01*
Y249229D01*
G01X803160Y259454D02*
X805314Y257300D01*
X806400D01*
G01X803150Y256336D02*
X801510Y257976D01*
Y260138D01*
X804045Y262673D01*
X810227D01*
X810500Y262400D01*
G01D02*
X814450Y258450D01*
Y257800D01*
G01X810950D02*
X808264Y255114D01*
X805114D01*
X804686Y254686D01*
X801991D01*
X800368Y256309D01*
X799972D01*
G01X810277Y243190D02*
X815370D01*
X815670Y242890D01*
G01D02*
X818560D01*
X821250Y240200D01*
G01X823100Y225400D02*
Y228000D01*
X821500Y229600D01*
X815400D01*
X814100Y230900D01*
Y235532D01*
X810688Y238944D01*
G01X818100Y225950D02*
X819950D01*
X820900Y225000D01*
X822700D01*
X823100Y225400D01*
G01X820050Y248200D02*
X820100Y248250D01*
Y252600D01*
G01X814100Y225950D02*
Y228400D01*
X811000Y231500D01*
Y234300D01*
G01X803129Y240535D02*
X806869D01*
X808981Y238423D01*
Y236319D01*
X811000Y234300D01*
G01X802000Y232500D02*
Y236256D01*
X803158Y237414D01*
G01X802000Y232500D02*
Y230500D01*
X806100Y226400D01*
Y225950D01*
G01X816400Y235900D02*
X811096Y241204D01*
X808960D01*
X806862Y243302D01*
G01X816400Y235900D02*
X816464Y235964D01*
X821218D01*
G01X807000Y230500D02*
X805670Y231830D01*
Y236556D01*
X806918Y237804D01*
G01X807000Y230500D02*
X810100Y227400D01*
Y225950D01*
G54D18*
X45906Y526995D03*
X38475D03*
X45906Y521269D03*
X38432Y521271D03*
X55100Y575850D03*
X50756Y571795D03*
X45906Y532622D03*
X38465Y532638D03*
X45985Y555153D03*
X38485D03*
X45906Y538249D03*
X38358Y538254D03*
X45906Y543876D03*
X38458Y543881D03*
X45985Y549526D03*
X38503Y549508D03*
X45985Y560879D03*
X38400Y560900D03*
X125770Y499350D03*
X127092Y602854D03*
X163600Y527700D03*
X149715Y464338D03*
Y472738D03*
X194315Y471838D03*
X149615Y476938D03*
X194415Y475938D03*
X172087Y587147D03*
X202040Y624780D03*
X181900Y635300D03*
X160500Y606760D03*
X203700Y641270D03*
X203200Y653100D03*
X197050Y607600D03*
X169502Y629826D03*
X211820Y491100D03*
X238600Y575100D03*
X238500Y558500D03*
X246300Y565900D03*
X238500Y550400D03*
X246317Y569957D03*
X265909Y587813D03*
X238500Y554400D03*
X238300Y562600D03*
Y566700D03*
X238600Y571000D03*
X246332Y579067D03*
X224148Y581666D03*
X240200Y539000D03*
X211800Y634500D03*
X222108Y637894D03*
X211108Y653294D03*
X331300Y512000D03*
X373800Y31000D03*
X371084Y626032D03*
X353600Y683400D03*
X344100Y687500D03*
X367100Y671900D03*
X454000Y33600D03*
X456500Y61900D03*
X438000Y37800D03*
X489794Y34455D03*
X710373Y253883D03*
X708979Y257964D03*
X685600Y265100D03*
X725130Y287930D03*
X685600Y269200D03*
X670000Y307400D03*
X776200Y182200D03*
X790073Y182318D03*
X761300Y180800D03*
X782990Y249880D03*
X804492Y182209D03*
X812228Y253664D03*
X814500Y314600D03*
G54D63*
X601500Y363600D03*
G54D54*
X380500Y24500D03*
X369500D03*
X467500Y25500D03*
X478500D03*
X744100Y474900D03*
X755100D03*
G54D72*
X755785Y91500D03*
X753585D03*
X755785Y94000D03*
X753585D03*
X755784Y99500D03*
X753584D03*
X755784Y102000D03*
X753584D03*
X755785Y83500D03*
X753585D03*
X755785Y75500D03*
X753585D03*
X755785Y78000D03*
X753585D03*
X755785Y86000D03*
X753585D03*
X778900Y206500D03*
X776700D03*
X792802Y206042D03*
X790602D03*
X760500Y204300D03*
X758300D03*
X778900Y208700D03*
X776700D03*
X792802Y208542D03*
X790602D03*
X760608Y284964D03*
X758408D03*
X789600Y280500D03*
X787400D03*
X781740Y269030D03*
X779540D03*
X765979Y284964D03*
X763779D03*
X807316Y206045D03*
X805116D03*
X807256Y208363D03*
X805056D03*
X806068Y278464D03*
X803868D03*
X805868Y270664D03*
X803668D03*
G54D45*
X165382Y475793D03*
Y473233D03*
Y470673D03*
Y468113D03*
X181562D03*
Y470673D03*
Y473233D03*
Y475793D03*
X326300Y675780D03*
Y673220D03*
Y670660D03*
Y668100D03*
Y665540D03*
Y662980D03*
Y660420D03*
X348500D03*
Y662980D03*
Y665540D03*
Y668100D03*
Y670660D03*
Y673220D03*
Y675780D03*
G54D36*
X103730Y576452D03*
X175569Y579940D03*
X204770Y552500D03*
X187720Y611240D03*
X225619Y634188D03*
X219320Y605070D03*
X215300Y638400D03*
X214700Y649500D03*
X325300Y681900D03*
X391400Y700700D03*
X371800Y689500D03*
X613300Y358900D03*
X726450Y256550D03*
X726150Y231460D03*
X726360Y225060D03*
X726300Y262300D03*
X733970Y227400D03*
X733960Y230840D03*
X726740Y249850D03*
X726970Y243700D03*
X726429Y237714D03*
X730950Y284210D03*
X726663Y268702D03*
X728700Y275200D03*
X746650Y249900D03*
X775100Y233900D03*
X765900Y262250D03*
X781000Y214700D03*
X741900Y218800D03*
X749400D03*
X781000Y218100D03*
X788519Y218074D03*
X764500Y269000D03*
X749768Y294464D03*
X736120Y288150D03*
X743660Y287810D03*
X804400Y246800D03*
G54D27*
X74400Y556700D03*
X102700Y507100D03*
X141107Y484000D03*
X132899Y489111D03*
X101800Y493000D03*
X126950Y495528D03*
X108492Y541947D03*
X138350Y584250D03*
X130400Y539899D03*
X126780Y562772D03*
X117121Y579998D03*
X123500Y613100D03*
X141971Y624700D03*
X105600Y597000D03*
X105400Y601300D03*
X104600Y609900D03*
X105600Y605900D03*
X104600Y614000D03*
X104500Y618800D03*
X116200Y611600D03*
X116023Y607423D03*
X119400Y614100D03*
X116400Y616900D03*
X134700Y604000D03*
X129903Y634500D03*
X118998Y701124D03*
X115598Y708228D03*
X109478Y713245D03*
X176000Y460200D03*
X171492Y496413D03*
X190416Y498361D03*
X183300Y493100D03*
X202190Y471014D03*
X202271Y475938D03*
X205447Y487762D03*
X162530Y500950D03*
X182874Y523590D03*
X165900Y524100D03*
X171571Y487041D03*
X176800Y495900D03*
X175700Y521000D03*
X199881Y507507D03*
X188065Y523962D03*
X203065Y493980D03*
X196200Y482600D03*
X158000Y476938D03*
X157800Y471800D03*
X158200Y467100D03*
X189500Y471900D03*
X190200Y476000D03*
X154660Y510100D03*
X195900Y503600D03*
X195379Y510158D03*
X153938Y526490D03*
X190603Y519531D03*
X152332Y583318D03*
X191100Y539700D03*
X180540Y539941D03*
X187600Y542450D03*
X203900Y542626D03*
X145150Y540250D03*
X175545Y539699D03*
X165085Y532153D03*
X169200Y534900D03*
X159327Y539484D03*
X152170Y593440D03*
X156501Y567965D03*
X194942Y536499D03*
X199700Y541100D03*
X206700Y539600D03*
X149093Y541418D03*
X197198Y595513D03*
X194490Y645390D03*
X196500Y603912D03*
X197300Y616100D03*
X198086Y624715D03*
X177378Y637409D03*
X150790Y598540D03*
X151550Y629800D03*
X163300Y602600D03*
X156669Y604185D03*
X153720Y614010D03*
X207569Y629750D03*
X201000Y603600D03*
X145710Y596640D03*
X185246Y603254D03*
X148000Y606650D03*
X184300Y594500D03*
X146800Y629900D03*
X204150Y645180D03*
X199600Y650100D03*
X192960Y628510D03*
X187900Y628500D03*
X162098Y697235D03*
X150849Y710215D03*
X155846Y723282D03*
X228700Y450600D03*
X238500Y448250D03*
X254500Y509600D03*
X222508Y479092D03*
X241947Y514306D03*
X228700Y490717D03*
X230700Y486658D03*
X249640Y495080D03*
X234700Y490900D03*
X219800Y490550D03*
X268448Y520801D03*
X233400Y560600D03*
X233100Y569900D03*
X262911Y568331D03*
X262603Y564342D03*
X233400Y579300D03*
X234722Y574814D03*
X224359Y562475D03*
X225530Y537192D03*
X253700Y531240D03*
X254905Y555761D03*
X232536Y588078D03*
X235700Y593300D03*
X237775Y545900D03*
X212000Y539600D03*
X265700Y580209D03*
X247000Y574567D03*
X253400Y571400D03*
X231000Y536584D03*
X238000Y532500D03*
X235772Y542321D03*
X212000Y608700D03*
X216000Y626900D03*
X218000Y630400D03*
X249700Y613590D03*
X213161Y623100D03*
X240900Y635200D03*
X227900Y606900D03*
X218968Y600635D03*
X215519Y594866D03*
X231066Y602763D03*
X253583Y653829D03*
X233100Y623400D03*
X256788Y697212D03*
X249090Y676611D03*
X259000Y672225D03*
X334200Y241900D03*
X312300Y247900D03*
X325147Y252424D03*
X313077Y257074D03*
X311464Y381211D03*
X339900Y454200D03*
X332816Y425682D03*
X339269Y407733D03*
X302175Y521026D03*
X286797Y516522D03*
X314370Y520789D03*
X292100Y516000D03*
X297400Y517981D03*
X327600Y515900D03*
X278400Y463300D03*
X333800Y534830D03*
X329840Y572710D03*
X301653Y572452D03*
X325475Y572818D03*
X322858Y560820D03*
X288700Y586900D03*
X322794Y568615D03*
X285564Y582990D03*
X298000Y561000D03*
X328580Y568120D03*
X320954Y572631D03*
X315500Y563050D03*
Y568700D03*
X340538Y563970D03*
X338200Y558000D03*
X337346Y545100D03*
X322423Y549010D03*
X315600Y557700D03*
X308200Y593153D03*
X325300Y648700D03*
X330400Y644300D03*
X327300Y655300D03*
X323191Y618260D03*
X333600Y628023D03*
X327250Y701500D03*
X333338Y696953D03*
X319950Y662500D03*
X303900Y661300D03*
X314250Y662600D03*
X303800Y681682D03*
X360600Y22300D03*
X365900Y67100D03*
X385673Y424903D03*
X389151Y436223D03*
X364577Y425023D03*
X390229Y508189D03*
X352111Y517737D03*
X373383Y511449D03*
X373800Y503000D03*
X378267Y496100D03*
X360300Y590390D03*
X344066Y579700D03*
X358100Y572200D03*
X344163Y553395D03*
X356300Y549100D03*
X364964Y588771D03*
X360500Y566200D03*
X377635Y616107D03*
X378800Y624850D03*
X342600Y682800D03*
X388017Y660594D03*
X362900Y683800D03*
X349190Y682490D03*
X377199Y699873D03*
X347010Y692076D03*
X341500Y707000D03*
X380387Y685261D03*
X392500Y673500D03*
X362700Y671900D03*
X458500Y27000D03*
X443500Y42000D03*
X439288Y46921D03*
X459700Y66000D03*
X436154Y72470D03*
X508100Y50100D03*
X495500Y61115D03*
X502930Y64170D03*
X489691Y42317D03*
X481093Y67669D03*
X494800Y74100D03*
X544814Y62686D03*
X564500Y64100D03*
X586155Y393023D03*
X627930Y198500D03*
X657603Y294530D03*
X652465Y294735D03*
X626988Y367660D03*
X604000Y501806D03*
X627408Y553791D03*
X640400Y557600D03*
X648800Y546000D03*
X715775Y261939D03*
X714226Y249665D03*
X695697Y269200D03*
X701654Y267100D03*
X693277Y313344D03*
X686714Y298448D03*
X695200Y301800D03*
X720900Y434172D03*
X734300Y496000D03*
X716442Y560260D03*
X699472Y560300D03*
X694000Y603000D03*
X711256Y595499D03*
X699899Y602970D03*
X768700Y180900D03*
X768579Y203964D03*
X787770Y254660D03*
X798770Y259500D03*
X796222Y208966D03*
X784200Y207100D03*
X744482Y202110D03*
X735300Y401957D03*
X755100Y486700D03*
X739300Y496000D03*
X755100Y481900D03*
X754883Y498500D03*
X810500Y262400D03*
X813491Y206953D03*
X820625Y345848D03*
X801880Y355479D03*
X817800Y479600D03*
X804100Y479200D03*
G54D82*
G01X13215Y-125739D02*
X14089Y-124864D01*
X14744Y-123406D01*
X15181Y-121363D01*
X14744Y-119614D01*
X13871Y-118447D01*
X12342Y-117572D01*
X6447D01*
Y-135072D01*
X13652D01*
X15181Y-133906D01*
X16054Y-132155D01*
X16491Y-130114D01*
X16054Y-128072D01*
X14744Y-126322D01*
X13215Y-125739D01*
X6447D01*
G01X25912Y-135072D02*
Y-123406D01*
G01Y-125739D02*
X27004Y-124572D01*
X28096Y-123697D01*
X29624Y-123406D01*
X30715Y-123697D01*
X32026Y-124572D01*
G01X41884Y-140322D02*
X43194Y-140905D01*
X44941Y-140322D01*
X46032Y-139156D01*
X46906Y-137697D01*
X48215Y-133031D01*
X51054Y-123406D01*
G01X44067D02*
X48215Y-133031D01*
G01X67462Y-124864D02*
X65934Y-123697D01*
X64624Y-123406D01*
X62877Y-123989D01*
X61567Y-125155D01*
X60694Y-127197D01*
X60475Y-129239D01*
X60694Y-131281D01*
X61567Y-133031D01*
X62877Y-134489D01*
X64624Y-135072D01*
X66152Y-134489D01*
X67462Y-133322D01*
G01X78194Y-127197D02*
X85181D01*
X84526Y-125155D01*
X83434Y-123989D01*
X81906Y-123406D01*
X80377Y-123697D01*
X79067Y-124572D01*
X78194Y-126614D01*
X77757Y-128364D01*
Y-130114D01*
X78194Y-131864D01*
X79286Y-133614D01*
X80596Y-134780D01*
X82124Y-135072D01*
X83652Y-134489D01*
X85181Y-132739D01*
G01X121272Y-119031D02*
X119962Y-118155D01*
X118434Y-117572D01*
X116687D01*
X114722Y-118447D01*
X113194Y-119905D01*
X112102Y-121656D01*
X111229Y-124572D01*
X111010Y-127197D01*
X111447Y-129822D01*
X112102Y-131572D01*
X113412Y-133322D01*
X114941Y-134489D01*
X116469Y-135072D01*
X117997D01*
X119526Y-134489D01*
X120836Y-133614D01*
X121928Y-132448D01*
G01X137899Y-135072D02*
Y-123406D01*
G01Y-125447D02*
X137026Y-124281D01*
X135715Y-123697D01*
X134187Y-123406D01*
X132659Y-123989D01*
X131349Y-125155D01*
X130475Y-126905D01*
X130039Y-129239D01*
X130475Y-131572D01*
X131349Y-133322D01*
X132659Y-134489D01*
X134187Y-135072D01*
X135715Y-134780D01*
X137026Y-133906D01*
X137899Y-132739D01*
G01X147757Y-135072D02*
Y-123406D01*
G01Y-126322D02*
X148631Y-124864D01*
X149941Y-123697D01*
X151687Y-123406D01*
X153215Y-123697D01*
X154526Y-124864D01*
X155181Y-126905D01*
Y-135072D01*
G01X164384Y-140322D02*
X165694Y-140905D01*
X167441Y-140322D01*
X168532Y-139156D01*
X169406Y-137697D01*
X170715Y-133031D01*
X173554Y-123406D01*
G01X166567D02*
X170715Y-133031D01*
G01X186469Y-135072D02*
X185159Y-134780D01*
X183849Y-133614D01*
X182975Y-131572D01*
X182539Y-129239D01*
X182975Y-126905D01*
X183849Y-124864D01*
X185159Y-123697D01*
X186469Y-123406D01*
X187779Y-123697D01*
X189089Y-124864D01*
X189962Y-126905D01*
X190181Y-129239D01*
X189962Y-131572D01*
X189089Y-133614D01*
X187779Y-134780D01*
X186469Y-135072D01*
G01X200257D02*
Y-123406D01*
G01Y-126322D02*
X201131Y-124864D01*
X202441Y-123697D01*
X204187Y-123406D01*
X205715Y-123697D01*
X207026Y-124864D01*
X207681Y-126905D01*
Y-135072D01*
G01X236349Y-117572D02*
X241589D01*
G01X238969D02*
Y-135072D01*
G01X236349D02*
X241589D01*
G01X256469D02*
X254722Y-134780D01*
X253194Y-133614D01*
X251884Y-131864D01*
X251010Y-129822D01*
X250574Y-127489D01*
Y-125155D01*
X251010Y-122822D01*
X251884Y-120780D01*
X253194Y-119031D01*
X254722Y-117864D01*
X256469Y-117572D01*
X258215Y-117864D01*
X259744Y-119031D01*
X261054Y-120780D01*
X261928Y-122822D01*
X262364Y-125155D01*
Y-127489D01*
X261928Y-129822D01*
X261054Y-131864D01*
X259744Y-133614D01*
X258215Y-134780D01*
X256469Y-135072D01*
G01X268292D02*
Y-117572D01*
X273969Y-132155D01*
X279646Y-117572D01*
Y-135072D01*
G01X307877Y-140905D02*
X305694Y-137989D01*
X304602Y-135072D01*
Y-123406D01*
X305694Y-120489D01*
X307877Y-117572D01*
G01X321010Y-123406D02*
X323631Y-135072D01*
X326469Y-123406D01*
X329307Y-135072D01*
X331928Y-123406D01*
G01X340039Y-135655D02*
X347899Y-117572D01*
G01X376349D02*
X381589D01*
G01X378969D02*
Y-135072D01*
G01X376349D02*
X381589D01*
G01X396469D02*
X394722Y-134780D01*
X393194Y-133614D01*
X391884Y-131864D01*
X391010Y-129822D01*
X390574Y-127489D01*
Y-125155D01*
X391010Y-122822D01*
X391884Y-120780D01*
X393194Y-119031D01*
X394722Y-117864D01*
X396469Y-117572D01*
X398215Y-117864D01*
X399744Y-119031D01*
X401054Y-120780D01*
X401928Y-122822D01*
X402364Y-125155D01*
Y-127489D01*
X401928Y-129822D01*
X401054Y-131864D01*
X399744Y-133614D01*
X398215Y-134780D01*
X396469Y-135072D01*
G01X418772Y-119031D02*
X417462Y-118155D01*
X415934Y-117572D01*
X414187D01*
X412222Y-118447D01*
X410694Y-119905D01*
X409602Y-121656D01*
X408729Y-124572D01*
X408510Y-127197D01*
X408947Y-129822D01*
X409602Y-131572D01*
X410912Y-133322D01*
X412441Y-134489D01*
X413969Y-135072D01*
X415497D01*
X417026Y-134489D01*
X418336Y-133614D01*
X419428Y-132448D01*
G01X432561Y-140905D02*
X434744Y-137989D01*
X435836Y-135072D01*
Y-123406D01*
X434744Y-120489D01*
X432561Y-117572D01*
G01X180792Y-90072D02*
Y-72572D01*
X186469Y-87155D01*
X192146Y-72572D01*
Y-90072D01*
G01X203969D02*
X202659Y-89780D01*
X201349Y-88614D01*
X200475Y-86572D01*
X200039Y-84239D01*
X200475Y-81905D01*
X201349Y-79864D01*
X202659Y-78697D01*
X203969Y-78406D01*
X205279Y-78697D01*
X206589Y-79864D01*
X207462Y-81905D01*
X207681Y-84239D01*
X207462Y-86572D01*
X206589Y-88614D01*
X205279Y-89780D01*
X203969Y-90072D01*
G01X225399Y-72572D02*
Y-90072D01*
G01Y-87448D02*
X224526Y-88906D01*
X223215Y-89780D01*
X221687Y-90072D01*
X219941Y-89489D01*
X218631Y-88031D01*
X217757Y-86281D01*
X217539Y-84239D01*
X217757Y-82197D01*
X218631Y-80447D01*
X219941Y-78989D01*
X221687Y-78406D01*
X223215Y-78697D01*
X224307Y-79281D01*
X225399Y-80447D01*
G01X235694Y-82197D02*
X242681D01*
X242026Y-80155D01*
X240934Y-78989D01*
X239406Y-78406D01*
X237877Y-78697D01*
X236567Y-79572D01*
X235694Y-81614D01*
X235257Y-83364D01*
Y-85114D01*
X235694Y-86864D01*
X236786Y-88614D01*
X238096Y-89780D01*
X239624Y-90072D01*
X241152Y-89489D01*
X242681Y-87739D01*
G01X256469Y-90072D02*
Y-72572D01*
G01X490269Y-135072D02*
Y-117572D01*
X487649Y-121072D01*
G01Y-135072D02*
X492889D01*
G01X503621Y-127781D02*
X505149Y-125739D01*
X506459Y-124572D01*
X508206Y-123989D01*
X509734Y-124572D01*
X510826Y-125739D01*
X511699Y-127489D01*
X511917Y-129530D01*
X511699Y-131281D01*
X510826Y-133031D01*
X509515Y-134489D01*
X507987Y-135072D01*
X506241Y-134489D01*
X504712Y-132739D01*
X503839Y-130114D01*
X503621Y-127197D01*
X504057Y-123406D01*
X504712Y-121363D01*
X505804Y-119322D01*
X507332Y-117864D01*
X508861Y-117572D01*
X510389Y-118155D01*
X511481Y-119614D01*
G01X520466Y-131572D02*
X521775Y-133614D01*
X523522Y-134780D01*
X525487Y-135072D01*
X527234Y-134780D01*
X528981Y-133322D01*
X530072Y-131572D01*
X530291Y-129822D01*
X529854Y-127781D01*
X528326Y-126322D01*
X526797Y-125739D01*
X524832D01*
G01X526797D02*
X528107Y-124864D01*
X529199Y-123406D01*
X529636Y-121656D01*
X529199Y-119905D01*
X528107Y-118447D01*
X526142Y-117572D01*
X524177Y-117864D01*
X522212Y-119031D01*
G01X542769Y-135072D02*
Y-117572D01*
X540149Y-121072D01*
G01Y-135072D02*
X545389D01*
G01X560269D02*
X561797Y-134780D01*
X563544Y-133906D01*
X564636Y-132448D01*
X565072Y-130405D01*
X564636Y-128364D01*
X563326Y-126614D01*
X561361Y-125739D01*
X559177D01*
X557867Y-125155D01*
X556775Y-123697D01*
X556339Y-121656D01*
X556994Y-119614D01*
X558522Y-118155D01*
X560269Y-117572D01*
X562015Y-118155D01*
X563544Y-119614D01*
X564199Y-121656D01*
X563762Y-123697D01*
X562671Y-125155D01*
X561361Y-125739D01*
X559177D01*
X557212Y-126614D01*
X555902Y-128364D01*
X555466Y-130405D01*
X555902Y-132448D01*
X556994Y-133906D01*
X558741Y-134780D01*
X560269Y-135072D01*
G01X477152Y-90072D02*
Y-72572D01*
X482392D01*
X484139Y-73447D01*
X485449Y-75489D01*
X485886Y-77822D01*
X485449Y-80155D01*
X484357Y-81905D01*
X482392Y-82781D01*
X477152D01*
G01X503822Y-74031D02*
X502512Y-73155D01*
X500984Y-72572D01*
X499237D01*
X497272Y-73447D01*
X495744Y-74905D01*
X494652Y-76656D01*
X493779Y-79572D01*
X493560Y-82197D01*
X493997Y-84822D01*
X494652Y-86572D01*
X495962Y-88322D01*
X497491Y-89489D01*
X499019Y-90072D01*
X500547D01*
X502076Y-89489D01*
X503386Y-88614D01*
X504478Y-87448D01*
G01X518265Y-80739D02*
X519139Y-79864D01*
X519794Y-78406D01*
X520231Y-76363D01*
X519794Y-74614D01*
X518921Y-73447D01*
X517392Y-72572D01*
X511497D01*
Y-90072D01*
X518702D01*
X520231Y-88906D01*
X521104Y-87155D01*
X521541Y-85114D01*
X521104Y-83072D01*
X519794Y-81322D01*
X518265Y-80739D01*
X511497D01*
G01X527469Y-95905D02*
X540569D01*
G01X546497Y-90072D02*
Y-72572D01*
X556541Y-90072D01*
Y-72572D01*
G01X569019Y-90072D02*
X567272Y-89780D01*
X565744Y-88614D01*
X564434Y-86864D01*
X563560Y-84822D01*
X563124Y-82489D01*
Y-80155D01*
X563560Y-77822D01*
X564434Y-75780D01*
X565744Y-74031D01*
X567272Y-72864D01*
X569019Y-72572D01*
X570765Y-72864D01*
X572294Y-74031D01*
X573604Y-75780D01*
X574478Y-77822D01*
X574914Y-80155D01*
Y-82489D01*
X574478Y-84822D01*
X573604Y-86864D01*
X572294Y-88614D01*
X570765Y-89780D01*
X569019Y-90072D01*
G01X647421Y-120489D02*
X648731Y-118739D01*
X650259Y-117864D01*
X652006Y-117572D01*
X654189Y-118155D01*
X655717Y-119614D01*
X656154Y-121363D01*
X655936Y-123114D01*
X655062Y-124572D01*
X650696Y-127489D01*
X648731Y-129530D01*
X647421Y-132448D01*
X646984Y-135072D01*
X656154D01*
G01X619860Y-72572D02*
X625319Y-90072D01*
X630778Y-72572D01*
G01X647186Y-90072D02*
X638452D01*
Y-72572D01*
X647186D01*
G01X643692Y-81030D02*
X638452D01*
G01X655952Y-90072D02*
Y-72572D01*
X661411D01*
X663157Y-73447D01*
X664249Y-74614D01*
X664686Y-76947D01*
X664249Y-79281D01*
X662939Y-80739D01*
X661411Y-81614D01*
X655952D01*
G01X661411D02*
X664686Y-90072D01*
G01X677819Y-90655D02*
X677382Y-90364D01*
Y-89780D01*
X677819Y-89489D01*
X678256Y-89780D01*
Y-90364D01*
X677819Y-90655D01*
G01X805886Y-117572D02*
Y-135072D01*
X797152D01*
G01X784019D02*
X782491Y-134780D01*
X780744Y-133906D01*
X779652Y-132448D01*
X779216Y-130405D01*
X779652Y-128364D01*
X780962Y-126614D01*
X782927Y-125739D01*
X785111D01*
X786421Y-125155D01*
X787513Y-123697D01*
X787949Y-121656D01*
X787294Y-119614D01*
X785766Y-118155D01*
X784019Y-117572D01*
X782273Y-118155D01*
X780744Y-119614D01*
X780089Y-121656D01*
X780526Y-123697D01*
X781617Y-125155D01*
X782927Y-125739D01*
X785111D01*
X787076Y-126614D01*
X788386Y-128364D01*
X788822Y-130405D01*
X788386Y-132448D01*
X787294Y-133906D01*
X785547Y-134780D01*
X784019Y-135072D01*
G01X753402Y-72572D02*
Y-90072D01*
X762136D01*
G01X779199D02*
Y-78406D01*
G01Y-80447D02*
X778326Y-79281D01*
X777015Y-78697D01*
X775487Y-78406D01*
X773959Y-78989D01*
X772649Y-80155D01*
X771775Y-81905D01*
X771339Y-84239D01*
X771775Y-86572D01*
X772649Y-88322D01*
X773959Y-89489D01*
X775487Y-90072D01*
X777015Y-89780D01*
X778326Y-88906D01*
X779199Y-87739D01*
G01X788184Y-95322D02*
X789494Y-95905D01*
X791241Y-95322D01*
X792332Y-94156D01*
X793206Y-92697D01*
X794515Y-88031D01*
X797354Y-78406D01*
G01X790367D02*
X794515Y-88031D01*
G01X806994Y-82197D02*
X813981D01*
X813326Y-80155D01*
X812234Y-78989D01*
X810706Y-78406D01*
X809177Y-78697D01*
X807867Y-79572D01*
X806994Y-81614D01*
X806557Y-83364D01*
Y-85114D01*
X806994Y-86864D01*
X808086Y-88614D01*
X809396Y-89780D01*
X810924Y-90072D01*
X812452Y-89489D01*
X813981Y-87739D01*
G01X824712Y-90072D02*
Y-78406D01*
G01Y-80739D02*
X825804Y-79572D01*
X826896Y-78697D01*
X828424Y-78406D01*
X829515Y-78697D01*
X830826Y-79572D01*
G01X917819Y-135072D02*
X916072Y-134780D01*
X914544Y-133614D01*
X913234Y-131864D01*
X912360Y-129822D01*
X911924Y-127489D01*
Y-125155D01*
X912360Y-122822D01*
X913234Y-120780D01*
X914544Y-119031D01*
X916072Y-117864D01*
X917819Y-117572D01*
X919565Y-117864D01*
X921094Y-119031D01*
X922404Y-120780D01*
X923278Y-122822D01*
X923714Y-125155D01*
Y-127489D01*
X923278Y-129822D01*
X922404Y-131864D01*
X921094Y-133614D01*
X919565Y-134780D01*
X917819Y-135072D01*
G01X919565Y-130405D02*
X922186Y-135072D01*
G01X930516Y-117572D02*
Y-130114D01*
X931389Y-132739D01*
X933136Y-134489D01*
X935319Y-135072D01*
X937502Y-134489D01*
X939249Y-132739D01*
X940122Y-130114D01*
Y-117572D01*
G01X950199D02*
X955439D01*
G01X952819D02*
Y-135072D01*
G01X950199D02*
X955439D01*
G01X965297D02*
Y-117572D01*
X975341Y-135072D01*
Y-117572D01*
G01X992622Y-119031D02*
X991312Y-118155D01*
X989784Y-117572D01*
X988037D01*
X986072Y-118447D01*
X984544Y-119905D01*
X983452Y-121656D01*
X982579Y-124572D01*
X982360Y-127197D01*
X982797Y-129822D01*
X983452Y-131572D01*
X984762Y-133322D01*
X986291Y-134489D01*
X987819Y-135072D01*
X989347D01*
X990876Y-134489D01*
X992186Y-133614D01*
X993278Y-132448D01*
G01X1005319Y-135072D02*
Y-127197D01*
X1000952Y-117572D01*
G01X1009686D02*
X1005319Y-127197D01*
G01X895516Y-90072D02*
Y-72572D01*
X899882D01*
X901629Y-73447D01*
X902939Y-74614D01*
X904031Y-76363D01*
X904904Y-78406D01*
X905122Y-81322D01*
X904904Y-84239D01*
X904031Y-86281D01*
X902939Y-88031D01*
X901629Y-89197D01*
X899882Y-90072D01*
X895516D01*
G01X914544Y-82197D02*
X921531D01*
X920876Y-80155D01*
X919784Y-78989D01*
X918256Y-78406D01*
X916727Y-78697D01*
X915417Y-79572D01*
X914544Y-81614D01*
X914107Y-83364D01*
Y-85114D01*
X914544Y-86864D01*
X915636Y-88614D01*
X916946Y-89780D01*
X918474Y-90072D01*
X920002Y-89489D01*
X921531Y-87739D01*
G01X932044Y-88031D02*
X933136Y-89197D01*
X934664Y-90072D01*
X935974D01*
X937284Y-89489D01*
X938157Y-88614D01*
X938594Y-87448D01*
X938376Y-85697D01*
X937502Y-84822D01*
X933572Y-83072D01*
X932699Y-81030D01*
X933136Y-79572D01*
X934009Y-78697D01*
X935319Y-78406D01*
X936629Y-78697D01*
X937939Y-79572D01*
G01X952819Y-78406D02*
Y-90072D01*
G01Y-73739D02*
X952382Y-73447D01*
Y-72864D01*
X952819Y-72572D01*
X953256Y-72864D01*
Y-73447D01*
X952819Y-73739D01*
G01X967262Y-94447D02*
X968791Y-95614D01*
X970537Y-95905D01*
X972065Y-95614D01*
X973376Y-94156D01*
X974249Y-92114D01*
Y-78406D01*
G01Y-80739D02*
X973376Y-79572D01*
X972065Y-78697D01*
X970537Y-78406D01*
X968791Y-78989D01*
X967699Y-80155D01*
X966825Y-82197D01*
X966389Y-84239D01*
X966607Y-85989D01*
X967481Y-88031D01*
X968791Y-89489D01*
X970537Y-90072D01*
X971847Y-89780D01*
X973376Y-88614D01*
X974249Y-87448D01*
G01X984107Y-90072D02*
Y-78406D01*
G01Y-81322D02*
X984981Y-79864D01*
X986291Y-78697D01*
X988037Y-78406D01*
X989565Y-78697D01*
X990876Y-79864D01*
X991531Y-81905D01*
Y-90072D01*
G01X1002044Y-82197D02*
X1009031D01*
X1008376Y-80155D01*
X1007284Y-78989D01*
X1005756Y-78406D01*
X1004227Y-78697D01*
X1002917Y-79572D01*
X1002044Y-81614D01*
X1001607Y-83364D01*
Y-85114D01*
X1002044Y-86864D01*
X1003136Y-88614D01*
X1004446Y-89780D01*
X1005974Y-90072D01*
X1007502Y-89489D01*
X1009031Y-87739D01*
G01X1019762Y-90072D02*
Y-78406D01*
G01Y-80739D02*
X1020854Y-79572D01*
X1021946Y-78697D01*
X1023474Y-78406D01*
X1024565Y-78697D01*
X1025876Y-79572D01*
G01X1066519Y-117572D02*
X1064772Y-118155D01*
X1063462Y-119614D01*
X1062589Y-121363D01*
X1061934Y-123697D01*
X1061716Y-126322D01*
X1061934Y-128947D01*
X1062589Y-131281D01*
X1063462Y-133031D01*
X1064772Y-134489D01*
X1066519Y-135072D01*
X1068265Y-134489D01*
X1069576Y-133031D01*
X1070449Y-131281D01*
X1071104Y-128947D01*
X1071322Y-126322D01*
X1071104Y-123697D01*
X1070449Y-121363D01*
X1069576Y-119614D01*
X1068265Y-118155D01*
X1066519Y-117572D01*
G01X1084019Y-135072D02*
X1085547Y-134780D01*
X1087294Y-133906D01*
X1088386Y-132448D01*
X1088822Y-130405D01*
X1088386Y-128364D01*
X1087076Y-126614D01*
X1085111Y-125739D01*
X1082927D01*
X1081617Y-125155D01*
X1080525Y-123697D01*
X1080089Y-121656D01*
X1080744Y-119614D01*
X1082272Y-118155D01*
X1084019Y-117572D01*
X1085765Y-118155D01*
X1087294Y-119614D01*
X1087949Y-121656D01*
X1087512Y-123697D01*
X1086421Y-125155D01*
X1085111Y-125739D01*
X1082927D01*
X1080962Y-126614D01*
X1079652Y-128364D01*
X1079216Y-130405D01*
X1079652Y-132448D01*
X1080744Y-133906D01*
X1082491Y-134780D01*
X1084019Y-135072D01*
G01X1097589Y-135655D02*
X1105449Y-117572D01*
G01X1119019D02*
X1117272Y-118155D01*
X1115962Y-119614D01*
X1115089Y-121363D01*
X1114434Y-123697D01*
X1114216Y-126322D01*
X1114434Y-128947D01*
X1115089Y-131281D01*
X1115962Y-133031D01*
X1117272Y-134489D01*
X1119019Y-135072D01*
X1120765Y-134489D01*
X1122076Y-133031D01*
X1122949Y-131281D01*
X1123604Y-128947D01*
X1123822Y-126322D01*
X1123604Y-123697D01*
X1122949Y-121363D01*
X1122076Y-119614D01*
X1120765Y-118155D01*
X1119019Y-117572D01*
G01X1136082Y-135072D02*
X1136519Y-131281D01*
X1137174Y-128072D01*
X1138047Y-125155D01*
X1139139Y-121947D01*
X1140886Y-117572D01*
X1132152D01*
G01X1150089Y-135655D02*
X1157949Y-117572D01*
G01X1167371Y-120489D02*
X1168681Y-118739D01*
X1170209Y-117864D01*
X1171956Y-117572D01*
X1174139Y-118155D01*
X1175667Y-119614D01*
X1176104Y-121363D01*
X1175886Y-123114D01*
X1175012Y-124572D01*
X1170646Y-127489D01*
X1168681Y-129530D01*
X1167371Y-132448D01*
X1166934Y-135072D01*
X1176104D01*
G01X1189019Y-117572D02*
X1187272Y-118155D01*
X1185962Y-119614D01*
X1185089Y-121363D01*
X1184434Y-123697D01*
X1184216Y-126322D01*
X1184434Y-128947D01*
X1185089Y-131281D01*
X1185962Y-133031D01*
X1187272Y-134489D01*
X1189019Y-135072D01*
X1190765Y-134489D01*
X1192076Y-133031D01*
X1192949Y-131281D01*
X1193604Y-128947D01*
X1193822Y-126322D01*
X1193604Y-123697D01*
X1192949Y-121363D01*
X1192076Y-119614D01*
X1190765Y-118155D01*
X1189019Y-117572D01*
G01X1206519Y-135072D02*
Y-117572D01*
X1203899Y-121072D01*
G01Y-135072D02*
X1209139D01*
G01X1223582D02*
X1224019Y-131281D01*
X1224674Y-128072D01*
X1225547Y-125155D01*
X1226639Y-121947D01*
X1228386Y-117572D01*
X1219652D01*
G01X1114216Y-90072D02*
Y-72572D01*
X1118582D01*
X1120329Y-73447D01*
X1121639Y-74614D01*
X1122731Y-76363D01*
X1123604Y-78406D01*
X1123822Y-81322D01*
X1123604Y-84239D01*
X1122731Y-86281D01*
X1121639Y-88031D01*
X1120329Y-89197D01*
X1118582Y-90072D01*
X1114216D01*
G01X1140449D02*
Y-78406D01*
G01Y-80447D02*
X1139576Y-79281D01*
X1138265Y-78697D01*
X1136737Y-78406D01*
X1135209Y-78989D01*
X1133899Y-80155D01*
X1133025Y-81905D01*
X1132589Y-84239D01*
X1133025Y-86572D01*
X1133899Y-88322D01*
X1135209Y-89489D01*
X1136737Y-90072D01*
X1138265Y-89780D01*
X1139576Y-88906D01*
X1140449Y-87739D01*
G01X1154019Y-72572D02*
Y-90072D01*
G01X1150962Y-78406D02*
X1157076D01*
G01X1168244Y-82197D02*
X1175231D01*
X1174576Y-80155D01*
X1173484Y-78989D01*
X1171956Y-78406D01*
X1170427Y-78697D01*
X1169117Y-79572D01*
X1168244Y-81614D01*
X1167807Y-83364D01*
Y-85114D01*
X1168244Y-86864D01*
X1169336Y-88614D01*
X1170646Y-89780D01*
X1172174Y-90072D01*
X1173702Y-89489D01*
X1175231Y-87739D01*
G54D19*
X65400Y546000D03*
X78231Y562399D03*
X92870Y564415D03*
X97113Y564386D03*
X100619Y564385D03*
X137100Y592000D03*
X133600D03*
X207500Y495580D03*
X252670Y620437D03*
X224346Y621995D03*
X245200Y688300D03*
X365400Y508000D03*
X367600Y701900D03*
X645000Y552900D03*
X721400Y278200D03*
X790360Y239400D03*
G54D55*
X373850Y563338D03*
X366350Y559463D03*
Y567213D03*
G54D64*
X629921Y57874D03*
X708661D03*
G54D37*
X96287Y576499D03*
X307900Y514300D03*
X356600Y524400D03*
X356480Y590440D03*
X378500Y578300D03*
X647500Y203400D03*
X648698Y299889D03*
X799200Y218150D03*
X795719Y218124D03*
X797099Y243345D03*
X796829Y234125D03*
X792269Y218094D03*
X764900Y213800D03*
X768479Y212264D03*
X759000Y214700D03*
X806210Y218140D03*
X802650Y218130D03*
G54D73*
X750150Y255200D03*
X752350D03*
X750300Y248900D03*
X752500D03*
X744000Y257400D03*
X746200D03*
X762600Y255200D03*
X764800D03*
X762600Y257400D03*
X764800D03*
X768700Y255150D03*
X770900D03*
X762550Y248900D03*
X764750D03*
X744050Y244850D03*
X746250D03*
X768700Y257350D03*
X770900D03*
X756400Y257400D03*
X758600D03*
X762550Y251100D03*
X764750D03*
X756400Y242600D03*
X758600D03*
X768950Y248940D03*
X771150D03*
X756400Y244800D03*
X758600D03*
X744050Y242600D03*
X746250D03*
X744000Y255200D03*
X746200D03*
X750300Y251100D03*
X752500D03*
X750207Y244805D03*
X752407D03*
X750200Y242600D03*
X752400D03*
X756400Y255200D03*
X758600D03*
X750150Y257400D03*
X752350D03*
X756450Y248900D03*
X758650D03*
X756450Y251100D03*
X758650D03*
X762600Y242600D03*
X764800D03*
X762600Y244800D03*
X764800D03*
X768950Y251140D03*
X771150D03*
X799400Y309500D03*
Y307000D03*
X788000Y269000D03*
X790200D03*
X780410Y276020D03*
X782610D03*
X780100Y279980D03*
X782300D03*
X775890Y284820D03*
X778090D03*
X786293Y285800D03*
X788493D03*
X785390Y266010D03*
X787590D03*
X786020Y283030D03*
X788220D03*
X801600Y309500D03*
Y307000D03*
X803800Y273800D03*
X806000D03*
G54D46*
X193238Y465985D03*
G54D28*
X65900Y671000D03*
X65700Y660900D03*
X70600Y665800D03*
X60700Y665900D03*
X70800Y660700D03*
X60800Y660900D03*
X70700Y671000D03*
X60600Y670900D03*
X65714Y665850D03*
X135019Y706095D03*
X130019D03*
X139916Y705822D03*
X130019Y724095D03*
X135019Y714845D03*
Y719095D03*
Y723595D03*
Y710595D03*
X130019Y720495D03*
Y716895D03*
Y713295D03*
Y709695D03*
X139916Y723822D03*
Y720222D03*
Y716622D03*
Y713022D03*
Y709422D03*
X306486Y643750D03*
X306286Y633650D03*
X311186Y638550D03*
X301286Y638650D03*
X311386Y633450D03*
X301386Y633650D03*
X311286Y643750D03*
X301186Y643650D03*
X306300Y638600D03*
X295634Y710070D03*
X290520Y715120D03*
X300620Y715220D03*
X290720Y705120D03*
X300720Y704920D03*
X290620Y710120D03*
X300520Y710020D03*
X295620Y705120D03*
X295820Y715220D03*
X316000Y671850D03*
X371400Y606400D03*
X358900Y612800D03*
X358800Y606300D03*
X365300Y606500D03*
X371400Y612700D03*
X371300Y618800D03*
X365500Y619000D03*
X358900Y618800D03*
X365164Y612620D03*
X468000Y35400D03*
X464000Y35500D03*
X468000Y39500D03*
Y31500D03*
X472000Y35500D03*
X601500Y363600D03*
X665500Y201900D03*
X657500Y281500D03*
X648000Y281300D03*
X629200Y536040D03*
X629080Y539920D03*
X625500Y536100D03*
X625300Y539900D03*
X700546Y577599D03*
X691796D03*
X691296Y572599D03*
X705696D03*
X696296Y577599D03*
X709296Y572599D03*
Y577599D03*
X702096Y572599D03*
X694896D03*
X698496D03*
X704796Y577599D03*
X709569Y582496D03*
X698769D03*
X695169D03*
X691569D03*
X702369D03*
X705969D03*
X810200Y494900D03*
X815100Y499800D03*
X805200Y499900D03*
X815300Y494700D03*
X805300Y494900D03*
X815200Y505000D03*
X805100Y504900D03*
X810214Y499850D03*
X810400Y505000D03*
G54D83*
G01X196710Y599340D02*
Y596001D01*
X197198Y595513D01*
G01X196710Y599340D02*
Y599746D01*
X194094Y602362D01*
G54D29*
X113900Y497300D03*
X165935Y481762D03*
X152316Y570304D03*
X175579Y583387D03*
X179260Y611180D03*
Y607480D03*
X207350Y633450D03*
X266805Y549594D03*
X236400Y633900D03*
X359600Y541400D03*
X369089Y554000D03*
X560800Y64700D03*
X584600Y77400D03*
X665800Y421500D03*
Y417500D03*
Y413500D03*
Y426000D03*
X727268Y294464D03*
X790750Y234770D03*
X757100Y262350D03*
X790900Y224400D03*
X790750Y231350D03*
Y227900D03*
X749600Y262350D03*
X748250Y268900D03*
X734768Y294464D03*
X742268D03*
X756050Y268900D03*
G54D56*
X361800Y603500D03*
Y599900D03*
X367620Y603164D03*
Y599564D03*
G54D74*
X735969Y481247D03*
G54D38*
X96287Y572899D03*
X307900Y510700D03*
X356600Y520800D03*
X356480Y586840D03*
X378500Y574700D03*
X647500Y199800D03*
X648698Y296289D03*
X799200Y214550D03*
X795719Y214524D03*
X797099Y239745D03*
X796829Y230525D03*
X792269Y214494D03*
X764900Y210200D03*
X768479Y208664D03*
X759000Y211100D03*
X806210Y214540D03*
X802650Y214530D03*
G54D65*
X638780Y69685D03*
X629921D03*
X621063D03*
X641732Y117323D03*
X638780Y114567D03*
X635827Y120079D03*
X632873Y117323D03*
X629921Y114567D03*
X626969Y120079D03*
X624015Y117323D03*
X621063Y114567D03*
X618110Y120079D03*
X641732Y102362D03*
X638780Y99606D03*
X635827Y105118D03*
X632873Y102362D03*
X629921Y99606D03*
X621063D03*
X624015Y102362D03*
X626969Y105118D03*
X618110D03*
X641732Y87402D03*
X638780Y84646D03*
X635827Y90157D03*
X632873Y87402D03*
X626969Y90157D03*
X629921Y84646D03*
X624015Y87402D03*
X621063Y84646D03*
X618110Y90157D03*
X641732Y72441D03*
X635827Y75197D03*
X632873Y72441D03*
X626969Y75197D03*
X624015Y72441D03*
X618110Y75197D03*
X717520Y69685D03*
X708661D03*
X699803D03*
X720472Y117323D03*
X717520Y114567D03*
X714567Y120079D03*
X711613Y117323D03*
X708661Y114567D03*
X705709Y120079D03*
X702755Y117323D03*
X699803Y114567D03*
X696850Y120079D03*
X720472Y102362D03*
X717520Y99606D03*
X714567Y105118D03*
X711613Y102362D03*
X708661Y99606D03*
X699803D03*
X702755Y102362D03*
X705709Y105118D03*
X696850D03*
X720472Y87402D03*
X717520Y84646D03*
X714567Y90157D03*
X711613Y87402D03*
X705709Y90157D03*
X708661Y84646D03*
X702755Y87402D03*
X699803Y84646D03*
X696850Y90157D03*
X720472Y72441D03*
X714567Y75197D03*
X711613Y72441D03*
X705709Y75197D03*
X702755Y72441D03*
X696850Y75197D03*
G54D47*
G01X204720Y552500D02*
Y553148D01*
X206692Y555120D01*
G01X175852Y574058D02*
Y576712D01*
X175298Y577266D01*
X197243Y589764D03*
X203542Y592913D03*
X168898Y548819D03*
X172000Y577150D03*
X184645Y589764D03*
X175197D03*
X209842Y583464D03*
X187795Y570866D03*
X184646Y577165D03*
X187795D03*
X190945D03*
X190944Y574016D03*
X190945Y570866D03*
X187795Y574016D03*
X184646D03*
Y570866D03*
X187795Y564567D03*
X194094Y567716D03*
X190945D03*
X187795D03*
X184646D03*
X206692Y592913D03*
X184645Y539370D03*
X194094D03*
X203542Y545671D03*
X197243Y539371D03*
X206692Y555120D03*
X194093D03*
X184646D03*
X153149Y536221D03*
X165748Y558268D03*
X172048Y555120D03*
X156297Y558267D03*
X172048Y589764D03*
X168898D03*
Y561417D03*
Y570866D03*
X156299Y586614D03*
Y580315D03*
X159449Y567717D03*
X156299Y570866D03*
X197243Y592913D03*
X200393Y589764D03*
X187794Y586614D03*
X203542Y589764D03*
X187795Y592914D03*
X165748Y583464D03*
X209841Y574016D03*
X206692D03*
X165745Y564567D03*
X168895D03*
X159449Y561417D03*
X165748D03*
X172047D03*
X162598Y558268D03*
X168898D03*
X165748Y555118D03*
X159449D03*
X168898Y567717D03*
X159449Y570866D03*
X168898Y583464D03*
Y577165D03*
X159449Y586614D03*
X162598Y580315D03*
Y586614D03*
X165748D03*
X168898D03*
X159449Y577165D03*
X156299D03*
X168898Y580315D03*
X159449D03*
X162598Y577165D03*
X165748Y580315D03*
X162598Y583464D03*
X165748Y570866D03*
Y567717D03*
X162598D03*
X172047Y570866D03*
X162597Y555118D03*
X197243Y551970D03*
X194093D03*
X200395Y555120D03*
X181497Y551970D03*
Y589764D03*
X187795Y555120D03*
X206692Y564569D03*
Y561419D03*
Y558269D03*
Y567718D03*
X203543Y574017D03*
X206692Y583465D03*
X194093Y586614D03*
X178347Y551970D03*
X175197D03*
Y558268D03*
X178347Y589764D03*
X190945Y542519D03*
X172047Y545669D03*
Y551970D03*
X159449Y545671D03*
X162599Y545669D03*
X165749D03*
X184646Y548821D03*
Y545671D03*
X209842Y567717D03*
X184645Y542519D03*
X206692Y542521D03*
X209841Y577165D03*
X159449Y542521D03*
X156299Y545671D03*
X168898Y592913D03*
X181497Y545671D03*
X209842Y545669D03*
X165749Y548819D03*
X175197Y545671D03*
X162599Y542519D03*
X168898D03*
X156299Y542521D03*
X181496Y542520D03*
X159449Y548821D03*
X206692Y589763D03*
X172047Y548819D03*
X168898Y551969D03*
X162599Y548821D03*
X194093Y589764D03*
Y592913D03*
X162598Y561417D03*
X168898Y555119D03*
X181497Y548821D03*
X178346Y545670D03*
X206692Y586614D03*
X209842Y586613D03*
X209841Y592913D03*
X162595Y564567D03*
X162598Y570866D03*
X203542Y548821D03*
Y586614D03*
Y580315D03*
X178344Y577166D03*
X178346Y586615D03*
X181497Y586614D03*
X178347Y574018D03*
Y570868D03*
X190944Y586614D03*
X200394Y570866D03*
Y574016D03*
X203543Y561418D03*
Y564568D03*
X165748Y551968D03*
X159448D03*
X178346Y555119D03*
X178347Y564569D03*
X197245Y555118D03*
X190944D03*
X181497Y555120D03*
X172048Y564569D03*
X172047Y567717D03*
X175298Y577266D03*
X209842Y558268D03*
X190944Y589764D03*
Y592913D03*
X197244Y586615D03*
X200393Y586614D03*
X194094Y542519D03*
X209842Y564567D03*
X200393Y548819D03*
X209842Y561417D03*
Y589763D03*
X206692Y580315D03*
X209841D03*
X200393Y545669D03*
X206692Y545671D03*
X200393Y592913D03*
X159448Y589764D03*
Y592913D03*
X162598Y589764D03*
X165748D03*
Y592913D03*
X165749Y542519D03*
X175197Y592913D03*
X172048D03*
X209842Y555119D03*
Y551969D03*
X181497Y592913D03*
X197244Y545669D03*
X194094Y548820D03*
X209842Y548819D03*
X175197Y548821D03*
X168898Y545669D03*
X156300Y539371D03*
X194094Y545669D03*
X197244Y542520D03*
X194094Y602362D03*
X206692Y596063D03*
X194093D03*
X203605Y605450D03*
X200393Y596063D03*
X187795Y602363D03*
X153149Y605513D03*
X209841Y596063D03*
X190945Y599213D03*
X190944Y596063D03*
X187796Y599212D03*
X184645Y599213D03*
X159448Y596063D03*
X168898D03*
X203542Y602362D03*
Y599213D03*
X206692Y602362D03*
X203542Y596063D03*
X194094Y599213D03*
X162598Y596063D03*
X165748Y599213D03*
X168898D03*
X162598D03*
X159448D03*
X172048Y596063D03*
X178346Y596064D03*
X178347Y599213D03*
X181496Y596062D03*
X209841Y599212D03*
X206692Y599213D03*
X165748Y596063D03*
X175197D03*
Y599213D03*
X172048D03*
X219800Y445700D03*
X213874Y445226D03*
X216141Y580315D03*
X212992Y586614D03*
X216141Y577165D03*
X212991Y567718D03*
X216141Y583465D03*
Y586614D03*
Y564569D03*
X212992Y561417D03*
X216141Y567718D03*
X219293Y567717D03*
X212992Y580315D03*
X212991Y577165D03*
Y574016D03*
X216141D03*
Y561419D03*
X212991Y583465D03*
Y542519D03*
X212992Y589764D03*
Y555119D03*
Y558268D03*
X216142Y548820D03*
X216141Y555120D03*
Y558269D03*
X222441Y548820D03*
X219291D03*
X212992Y551969D03*
X216141Y551970D03*
X212992Y548819D03*
X216141Y589762D03*
X212993Y592912D03*
X212992Y564567D03*
Y545669D03*
X216142D03*
X222440Y605512D03*
X212992Y602363D03*
X212991Y599212D03*
X216141D03*
X762173Y294089D03*
X781088Y294094D03*
X771653Y294093D03*
X777952Y290944D03*
X777989Y294093D03*
X774802Y290944D03*
X774835Y294088D03*
X768503Y290944D03*
X768498Y294124D03*
X765353Y290944D03*
X765325Y294102D03*
X759054Y290944D03*
X759055Y294094D03*
X755905Y290944D03*
Y294093D03*
X787401Y290944D03*
X787408Y294074D03*
X784251Y290944D03*
X784258Y294064D03*
G54D84*
G01X190944Y592913D02*
Y589764D01*
G01X197244Y586615D02*
X197245Y586614D01*
X200393D01*
G54D75*
G01X666700Y205600D02*
X667300Y206200D01*
Y211250D01*
G01X647500Y203350D02*
X647615Y203465D01*
Y211250D01*
G01X677800Y215900D02*
X676100D01*
X675175Y214975D01*
Y211250D01*
G01X763779Y284964D02*
Y285693D01*
X762204Y287268D01*
Y287794D01*
G01X779540Y269030D02*
Y270523D01*
X781064Y272047D01*
G01X787590Y266010D02*
X790251D01*
X790538Y265723D01*
G01X782610Y276020D02*
Y276685D01*
X784243Y278318D01*
G01D02*
X782581Y279980D01*
X782300D01*
G01X775200Y280800D02*
X774526Y281474D01*
X771669D01*
G01X780100Y279980D02*
Y283645D01*
X781120Y284665D01*
G01X780410Y276020D02*
X780100Y276330D01*
Y279980D01*
G01X781740Y269030D02*
X784107D01*
X784252Y268885D01*
G01X785390Y266010D02*
X781327D01*
X781080Y265763D01*
G01X765979Y284964D02*
Y287168D01*
X765353Y287794D01*
G01X775890Y284820D02*
Y285732D01*
X777952Y287794D01*
G01X803868Y278464D02*
X800118D01*
X799999Y278345D01*
G01X806068Y278464D02*
X810579D01*
X811789Y279674D01*
X812164D01*
G54D48*
X163189Y669291D03*
G54D39*
X137824Y544746D03*
Y552346D03*
X135449Y558949D03*
Y566549D03*
X122600Y589800D03*
Y597400D03*
X149700Y723000D03*
Y715400D03*
X220300Y525700D03*
Y518100D03*
X247070Y619140D03*
Y626740D03*
X239346Y626876D03*
Y619276D03*
X312272Y192744D03*
Y200344D03*
X327612Y231754D03*
Y239354D03*
X327552Y225184D03*
Y217584D03*
X477943Y34165D03*
Y41765D03*
X679500Y302700D03*
Y310300D03*
X712780Y316840D03*
Y324440D03*
X770090Y226880D03*
Y219280D03*
X760650Y236070D03*
Y228470D03*
X741650Y235600D03*
Y228000D03*
X770300Y270000D03*
Y277600D03*
X801226Y361756D03*
Y369356D03*
X809326Y369256D03*
Y361656D03*
G54D57*
X367113Y622707D03*
Y626307D03*
X718590Y319060D03*
Y322660D03*
X726350Y319080D03*
Y322680D03*
X722390Y319060D03*
Y322660D03*
G54D66*
X651575Y20039D03*
X608267D03*
X641732Y126811D03*
X624015D03*
X651575Y72441D03*
X608267D03*
X730315Y20039D03*
X687007D03*
X720472Y126811D03*
X702755D03*
X730315Y72441D03*
X687007D03*
G54D85*
G01X63050Y569822D02*
X63731Y569141D01*
X65354D01*
X66278Y568217D01*
Y557122D01*
X66858Y556542D01*
X69427D01*
X71002Y558117D01*
G01X172047Y545669D02*
Y545647D01*
G01Y551970D02*
X175077Y555000D01*
X175200D01*
G01X197400Y549000D02*
X198700Y550300D01*
X206800D01*
X208167Y551667D01*
Y556593D01*
X209842Y558268D01*
G01X220832Y551776D02*
X219324D01*
X217556Y553544D01*
X215456D01*
X213881Y555119D01*
X212992D01*
G01X222600Y555029D02*
X218636D01*
X217070Y556595D01*
X214665D01*
X212992Y558268D01*
G01X216141Y555120D02*
X217484D01*
X218453Y554151D01*
X221949D01*
X223800Y552300D01*
Y550408D01*
X225932Y548276D01*
G01X221304Y558596D02*
X220497Y559403D01*
X217889D01*
X217392Y559900D01*
X212423D01*
X211317Y561006D01*
Y563092D01*
X209842Y564567D01*
G01X796868Y278364D02*
X797701Y279197D01*
X797826D01*
X798903Y280274D01*
X808058D01*
X809809Y282025D01*
X811848D01*
X812273Y281600D01*
X812360D01*
G01X811498Y276758D02*
X811411D01*
X810986Y276333D01*
X797606D01*
X795292Y274019D01*
X794152D01*
G02X793862Y274138I0J413D01*
G01X793861Y274139D01*
G02X793737Y274436I294J297D01*
G01Y275196D01*
G01X811498Y275158D02*
X811411D01*
X810986Y275583D01*
X797917D01*
X795589Y273255D01*
X795575Y273269D01*
X794191D01*
G03X793682Y272760I0J-509D01*
G01Y272064D01*
G01X816141Y269008D02*
X816054D01*
X815629Y268583D01*
X801199D01*
X799293Y270489D01*
X794889D01*
X793683Y269283D01*
Y268879D01*
G01X816141Y267408D02*
X816054D01*
X815629Y267833D01*
X800888D01*
X798982Y269739D01*
X797679D01*
X796850Y268910D01*
G01X816141Y264218D02*
X816054D01*
X815629Y263793D01*
X813571D01*
X811566Y265798D01*
X796087D01*
X794870Y264581D01*
X794089D01*
G02X793799Y264700I0J413D01*
G01X793798Y264701D01*
G02X793674Y264998I294J297D01*
G01Y265758D01*
G01X816141Y262618D02*
X816054D01*
X815629Y263043D01*
X813260D01*
X811255Y265048D01*
X796398D01*
X795181Y263831D01*
X794880D01*
G02X794876I-2J419D01*
G01X794128D01*
G03X793879Y263727I0J-350D01*
G01X793839Y263686D01*
G03X793699Y263344I348J-342D01*
G01Y262634D01*
G01X716582Y245259D02*
X719241D01*
X719686Y244814D01*
Y238976D01*
X718111Y237401D01*
G01X793675Y278357D02*
X795258Y279947D01*
X797515D01*
X798592Y281024D01*
X807747D01*
X809498Y282775D01*
X811848D01*
X812273Y283200D01*
X812360D01*
G01X718109Y272034D02*
X719685Y270458D01*
Y264952D01*
X718810Y264077D01*
G01X793700Y297243D02*
X794244D01*
G03X794669Y297419I0J601D01*
G03X794845Y297844I-425J425D01*
G01Y299268D01*
X796946Y301369D01*
X802529D01*
X802950Y301790D01*
G01X796849Y297243D02*
X796205D01*
G02X795773Y297422I0J611D01*
G02X795595Y297852I430J430D01*
G01Y298957D01*
X797257Y300619D01*
X802521D01*
X802950Y300190D01*
G01X804557Y297535D02*
X804470D01*
X804045Y297110D01*
X799768D01*
X797528Y294870D01*
X793352D01*
X791630Y293148D01*
Y291456D01*
G02X791484Y291105I-497J1D01*
G01X791442Y291062D01*
G02X791193Y290959I-248J247D01*
G01X790545D01*
G01X804557Y295935D02*
X804470D01*
X804045Y296360D01*
X800079D01*
X797839Y294120D01*
X793663D01*
X792380Y292837D01*
Y291490D01*
G03X792536Y291115I531J1D01*
G01X792588Y291062D01*
G03X792837Y290959I248J247D01*
G01X793694D01*
G01X793703Y287797D02*
X795255Y289349D01*
X796176D01*
X796186Y289359D01*
X799879D01*
X801052Y288186D01*
X803941D01*
X809430Y293675D01*
X815399D01*
X815824Y294100D01*
X815911D01*
G01X796839Y287784D02*
X797664Y288609D01*
X799568D01*
X800741Y287436D01*
X804252D01*
X809741Y292925D01*
X815399D01*
X815824Y292500D01*
X815911D01*
G01X805740Y285170D02*
X805653D01*
X805228Y284745D01*
X803379D01*
X801704Y283070D01*
X799346D01*
X798569Y283847D01*
X795536D01*
X795138Y283449D01*
X794101D01*
G02X793993Y283462I-3J426D01*
G02X793675Y283875I109J413D01*
G01Y284637D01*
G01X805740Y283570D02*
X805653D01*
X805228Y283995D01*
X803690D01*
X802015Y282320D01*
X799035D01*
X798258Y283097D01*
X795847D01*
X795449Y282699D01*
X794128D01*
G03X794113Y282698I22J-448D01*
G03X793679Y282264I0J-434D01*
G01Y281508D01*
G01X740158Y284646D02*
Y283725D01*
X741734Y282149D01*
Y280369D01*
X743503Y278600D01*
X743800D01*
G01X736800Y278300D02*
X735434Y279666D01*
Y283071D01*
X737009Y284646D01*
G54D76*
G01X186735Y463748D02*
Y465065D01*
X183687Y468113D01*
X181562D01*
G54D49*
X214040Y504230D03*
X216600D03*
X219160D03*
Y497730D03*
X214040D03*
G54D58*
X354800Y612600D03*
X351200D03*
X773200Y262450D03*
X769600D03*
X778390Y247880D03*
X774790D03*
X778550Y251850D03*
X774950D03*
G54D67*
X658585Y152347D03*
Y150147D03*
X656085Y152347D03*
Y150147D03*
X663784Y152447D03*
Y150247D03*
X661284Y152447D03*
Y150247D03*
X666685Y152447D03*
Y150247D03*
X653384Y152347D03*
Y150147D03*
X650884Y152347D03*
Y150147D03*
X669185Y152447D03*
Y150247D03*
X786880Y262090D03*
Y259890D03*
X781580Y261940D03*
Y259740D03*
X790800Y297700D03*
Y295500D03*
X770800Y302100D03*
Y299900D03*
X757000Y277950D03*
Y275750D03*
X752000Y288200D03*
Y286000D03*
X754800Y277950D03*
Y275750D03*
X775200Y280800D03*
Y278600D03*
X803100Y292800D03*
Y290600D03*
G54D86*
G01X81975Y554363D02*
X83192Y555580D01*
X86135D01*
X86750Y554965D01*
G01X81974Y558398D02*
X83192Y557180D01*
X85815D01*
X86750Y558115D01*
G01X669185Y150247D02*
X668731Y149793D01*
Y95670D01*
X647761Y74700D01*
X640798D01*
X640473Y74375D01*
X638529Y72287D01*
X638113Y71967D01*
G03X637913Y71304I232J-432D01*
G01X638780Y69685D01*
G01X666685Y150247D02*
X667131Y149801D01*
Y96333D01*
X664783Y93985D01*
X663284D01*
X662244Y92945D01*
Y91446D01*
X661205Y90407D01*
X659706D01*
X658666Y89367D01*
Y87868D01*
X647098Y76300D01*
X640135D01*
X639321Y75486D01*
X639302Y75466D01*
X637358Y73378D01*
G02X636694Y73578I-232J432D01*
G01X635827Y75197D01*
G01X629921Y69685D02*
X629054Y71302D01*
G02X629254Y71966I432J232D01*
G01X629255D01*
X629577Y72138D01*
X629668Y72187D01*
X630001Y72354D01*
X631516Y74449D01*
Y76262D01*
X635069Y79815D01*
X644499D01*
X663312Y98628D01*
Y149775D01*
X663784Y150247D01*
G01X661284D02*
X661712Y149819D01*
Y99291D01*
X660598Y98177D01*
X659099D01*
X658060Y97138D01*
Y95639D01*
X657020Y94599D01*
X655521D01*
X654482Y93560D01*
Y92061D01*
X643836Y81415D01*
X634406D01*
X629916Y76925D01*
Y74968D01*
X628934Y73610D01*
X628932Y73609D01*
X628911Y73598D01*
X628908Y73596D01*
X628500Y73378D01*
G02X627836Y73578I-232J432D01*
G01X626969Y75197D01*
G01X658585Y150147D02*
X658186Y149748D01*
Y102611D01*
X645743Y90166D01*
X641189D01*
X640264Y89241D01*
X639188Y87500D01*
X638584Y87177D01*
X638482Y87123D01*
X638310Y87031D01*
X638165Y86953D01*
X638141Y86941D01*
X638134Y86937D01*
X638114Y86927D01*
X638113D01*
G03X637913Y86263I232J-432D01*
G01X638780Y84646D01*
G01X656085Y150147D02*
X656586Y149642D01*
Y103274D01*
X655547Y102234D01*
X654048D01*
X653008Y101195D01*
Y99696D01*
X651969Y98656D01*
X650470D01*
X649431Y97617D01*
Y96118D01*
X645080Y91766D01*
X640526D01*
X639001Y90241D01*
X638053Y88709D01*
X637542Y88436D01*
X637415Y88369D01*
X637408Y88365D01*
X637386Y88354D01*
X637381Y88351D01*
X637375Y88348D01*
X637370Y88345D01*
X637364Y88342D01*
X637358Y88338D01*
G02X636694Y88538I-232J432D01*
G01X635827Y90157D01*
G01X653384Y150147D02*
X652884Y149647D01*
Y106491D01*
X641441Y95048D01*
X635487D01*
X631021Y90582D01*
Y88596D01*
X629450Y87025D01*
X629251Y86925D01*
X629054Y86263D01*
X629921Y84646D01*
G01X650884Y150147D02*
X651284Y149747D01*
Y133841D01*
X650224Y132781D01*
Y131311D01*
X651284Y130251D01*
Y128781D01*
X650224Y127721D01*
Y126251D01*
X651284Y125191D01*
Y107154D01*
X640778Y96648D01*
X634824D01*
X629421Y91245D01*
Y89259D01*
X628502Y88340D01*
X628500Y88339D01*
G02X627836Y88539I-232J432D01*
G01X626969Y90157D01*
G01X812360Y281600D02*
X827637D01*
X846333Y262904D01*
X848921Y249963D01*
X851508Y237025D01*
X846115Y210057D01*
X840723Y183089D01*
X835662Y175586D01*
X813294Y158965D01*
X739969Y144294D01*
X738642Y144552D01*
X735469Y145169D01*
X733375Y145575D01*
X732537Y146817D01*
X731094Y147098D01*
X729851Y146259D01*
X728408Y146540D01*
X727570Y147782D01*
X726127Y148063D01*
X724884Y147224D01*
X723441Y147505D01*
X722603Y148747D01*
X721160Y149028D01*
X719917Y148189D01*
X700258Y152008D01*
X699420Y153250D01*
X697977Y153531D01*
X696734Y152692D01*
X695291Y152972D01*
X694453Y154215D01*
X693010Y154495D01*
X691767Y153657D01*
X690324Y153937D01*
X689486Y155180D01*
X688043Y155460D01*
X686800Y154622D01*
X685357Y154902D01*
X684519Y156145D01*
X683076Y156425D01*
X681833Y155587D01*
X673377Y157229D01*
X668847Y156348D01*
X667552Y155053D01*
Y155052D01*
X667084Y154584D01*
Y152846D01*
X666685Y152447D01*
G01X663784D02*
X663184Y153047D01*
Y155279D01*
X668405Y160500D01*
X682496D01*
X742789Y148443D01*
X811917Y162272D01*
X832894Y178012D01*
X837513Y184860D01*
X842790Y211246D01*
X848066Y237630D01*
X847699Y239464D01*
X847396Y240985D01*
X846786Y244029D01*
X846787D01*
X845507Y250424D01*
X843107Y254029D01*
X840793Y257504D01*
X821539Y276758D01*
X811498D01*
G01X661284Y152447D02*
X661584Y152747D01*
Y155942D01*
X667742Y162100D01*
X682655D01*
X685807Y161470D01*
X687055Y162301D01*
X688496Y162013D01*
X689328Y160766D01*
X690769Y160477D01*
X692016Y161309D01*
X693458Y161021D01*
X694289Y159774D01*
X695731Y159485D01*
X696978Y160317D01*
X698420Y160029D01*
X699251Y158781D01*
Y158782D01*
X742789Y150075D01*
X811247Y163770D01*
X831718Y179130D01*
X836007Y185489D01*
X846434Y237630D01*
X844000Y249800D01*
X839549Y256485D01*
X820876Y275158D01*
X811498D01*
G01X658585Y152347D02*
X658090Y152842D01*
Y158441D01*
X665289Y165640D01*
X689250D01*
X746335Y154232D01*
X809631Y166897D01*
X828850Y181186D01*
X832708Y186902D01*
X842546Y236075D01*
X840361Y246995D01*
X840362D01*
X840295Y247326D01*
X838368Y250061D01*
X836635Y252519D01*
X836556Y252631D01*
X820179Y269008D01*
X816141D01*
G01X656085Y152347D02*
X656490Y152752D01*
Y159104D01*
X664626Y167240D01*
X689409D01*
X707465Y163632D01*
X708712Y164464D01*
X710153Y164175D01*
X710985Y162928D01*
X712427Y162640D01*
X713674Y163472D01*
X715115Y163184D01*
X715947Y161937D01*
X717388Y161649D01*
X718636Y162480D01*
X720077Y162192D01*
X720909Y160945D01*
X722350Y160657D01*
X723597Y161489D01*
X725039Y161201D01*
X725871Y159954D01*
X746335Y155864D01*
X808964Y168396D01*
X827676Y182307D01*
X831202Y187531D01*
X837871Y220868D01*
X837040Y222115D01*
X837328Y223557D01*
X838576Y224388D01*
X838864Y225830D01*
X838033Y227077D01*
X838321Y228518D01*
X839568Y229350D01*
X839857Y230791D01*
X839025Y232039D01*
X839314Y233480D01*
X840561Y234311D01*
X840914Y236075D01*
X838792Y246681D01*
X835327Y251597D01*
X819516Y267408D01*
X816141D01*
G01X653384Y152347D02*
X652884Y152847D01*
Y160272D01*
X663612Y171000D01*
X691926D01*
X736925Y162257D01*
X741550Y161358D01*
X745762Y160539D01*
X749179Y159874D01*
X777357Y165556D01*
X805538Y171238D01*
X825072Y184421D01*
X836175Y239863D01*
X835873Y241375D01*
X835852Y241480D01*
X835603Y242729D01*
X825602Y252730D01*
X825601D01*
X825600Y256768D01*
X818150Y264218D01*
X816141D01*
G01X650884Y152347D02*
X651284Y152747D01*
Y160935D01*
X662949Y172600D01*
X692081D01*
X715681Y168015D01*
X716924Y168853D01*
X718367Y168573D01*
X719205Y167330D01*
X720648Y167050D01*
X721891Y167888D01*
X723334Y167608D01*
X724172Y166365D01*
X725615Y166084D01*
X726858Y166923D01*
X728301Y166642D01*
X729139Y165400D01*
X740698Y163154D01*
X749173Y161506D01*
X804908Y172744D01*
X823632Y185380D01*
X834543Y239863D01*
X834304Y241060D01*
X834262Y241267D01*
X834128Y241940D01*
X824000Y252068D01*
Y256105D01*
X817487Y262618D01*
X816141D01*
G01X753585Y75500D02*
X753466Y75618D01*
X753106Y75978D01*
X749539D01*
X748479Y74918D01*
X747009D01*
X745949Y75978D01*
X725478D01*
X724200Y74700D01*
X719538D01*
X719213Y74375D01*
X717269Y72287D01*
X716853Y71967D01*
G03X716653Y71304I232J-432D01*
G01X717520Y69685D01*
G01X753585Y78000D02*
X753163Y77578D01*
X724815D01*
X723537Y76300D01*
X718875D01*
X718061Y75486D01*
X718042Y75466D01*
X716098Y73378D01*
G02X715434Y73578I-232J432D01*
G01X714567Y75197D01*
G01X753585Y83500D02*
X753171Y83914D01*
X747305D01*
X746245Y82854D01*
X744775D01*
X743715Y83914D01*
X725927D01*
X722213Y80200D01*
X714175D01*
X710256Y76281D01*
Y74450D01*
X708741Y72354D01*
X708408Y72187D01*
X708317Y72138D01*
X707995Y71966D01*
X707994D01*
G03X707794Y71302I232J-432D01*
G01X708661Y69685D01*
G01X753585Y86000D02*
X753099Y85514D01*
X725264D01*
X721550Y81800D01*
X713512D01*
X708656Y76944D01*
Y74968D01*
X707674Y73610D01*
X707672Y73609D01*
X707651Y73598D01*
X707648Y73596D01*
X707240Y73378D01*
G02X706576Y73578I-232J432D01*
G01X705709Y75197D01*
G01X717520Y84646D02*
X716653Y86263D01*
G02X716853Y86927I432J232D01*
G01X716854D01*
X716874Y86937D01*
X716881Y86941D01*
X716897Y86949D01*
X716904Y86953D01*
X716907Y86955D01*
X717928Y87500D01*
X719518Y90072D01*
X723254D01*
X725182Y92000D01*
X740487D01*
X741547Y90940D01*
X743017D01*
X744077Y92000D01*
X752400D01*
X752900Y91500D01*
X753585D01*
G01X714567Y90157D02*
X715434Y88538D01*
G03X716098Y88338I432J232D01*
G01X716104Y88342D01*
X716110Y88345D01*
X716115Y88348D01*
X716121Y88351D01*
X716126Y88354D01*
X716152Y88367D01*
X716793Y88708D01*
X718626Y91672D01*
X722591D01*
X724519Y93600D01*
X752500D01*
X752900Y94000D01*
X753585D01*
G01X753584Y99500D02*
X753121Y99963D01*
X741531D01*
X740471Y98903D01*
X739001D01*
X737941Y99963D01*
X725203D01*
X720799Y95559D01*
X714082D01*
X709761Y91238D01*
Y88596D01*
X708190Y87025D01*
X707991Y86925D01*
X707794Y86263D01*
X708661Y84646D01*
G01X753584Y102000D02*
X753147Y101563D01*
X724540D01*
X720136Y97159D01*
X713419D01*
X708161Y91901D01*
Y89259D01*
X707242Y88340D01*
X707240Y88339D01*
G02X706576Y88539I-232J432D01*
G01X705709Y90157D01*
G01X812360Y283200D02*
X828300D01*
X847807Y263693D01*
X853140Y237025D01*
X844988Y196259D01*
X842229Y182460D01*
X836836Y174464D01*
X813960Y157466D01*
X739973Y142663D01*
X738337Y142981D01*
X735164Y143598D01*
X734118Y143801D01*
X733070Y144004D01*
Y144003D01*
X673377Y155599D01*
X669633Y154870D01*
X668684Y153921D01*
Y152948D01*
X669185Y152447D01*
G01X802950Y301790D02*
X804180D01*
X807135Y304745D01*
X852817D01*
X863403Y294159D01*
X874993Y236171D01*
X857608Y149238D01*
X836982Y118292D01*
X832655Y115409D01*
Y115408D01*
X802554Y95349D01*
X773191Y75782D01*
X756067D01*
X755785Y75500D01*
G01X802950Y300190D02*
X804843D01*
X807798Y303145D01*
X852154D01*
X861929Y293370D01*
X873361Y236171D01*
X856101Y149862D01*
X835828Y119446D01*
X832319Y117108D01*
X830849Y117402D01*
X829625Y116587D01*
X829331Y115117D01*
X828108Y114302D01*
X826638Y114596D01*
X825415Y113781D01*
X825120Y112311D01*
X823897Y111496D01*
X822427Y111790D01*
X821204Y110975D01*
X820910Y109505D01*
X802218Y97049D01*
X800749Y97343D01*
X799526Y96528D01*
X799231Y95058D01*
X798008Y94243D01*
X796538Y94537D01*
X795315Y93722D01*
X795021Y92252D01*
X793797Y91437D01*
X792327Y91731D01*
X791104Y90916D01*
X790810Y89446D01*
X789587Y88631D01*
X788117Y88925D01*
X786893Y88110D01*
X786599Y86640D01*
X772706Y77382D01*
X756403D01*
X755785Y78000D01*
G01Y83500D02*
X756185Y83900D01*
X769249D01*
X776705Y85349D01*
X833868Y123452D01*
X853173Y152411D01*
X869946Y236289D01*
X859925Y286338D01*
X846408Y299855D01*
X811645D01*
X809325Y297535D01*
X804557D01*
G01X755785Y86000D02*
Y85999D01*
X756284Y85500D01*
X769094D01*
X776084Y86859D01*
Y86860D01*
X782190Y90930D01*
X782484Y92400D01*
X783707Y93215D01*
X785177Y92921D01*
X786401Y93736D01*
X786695Y95206D01*
X787918Y96022D01*
X789388Y95727D01*
X790611Y96543D01*
X790905Y98013D01*
X792128Y98828D01*
X793598Y98534D01*
X794821Y99349D01*
X795116Y100819D01*
X796339Y101634D01*
X797809Y101340D01*
X812658Y111238D01*
X812952Y112708D01*
X814175Y113523D01*
X815645Y113229D01*
X816868Y114044D01*
X817162Y115514D01*
X818385Y116329D01*
X819855Y116035D01*
X821078Y116850D01*
X821372Y118320D01*
X822596Y119136D01*
X824066Y118842D01*
X832714Y124606D01*
X851666Y153035D01*
X868314Y236289D01*
X858451Y285549D01*
X845745Y298255D01*
X812308D01*
X809988Y295935D01*
X804557D01*
G01X815911Y294100D02*
X839399D01*
X856832Y276667D01*
X864379Y238921D01*
X848490Y157186D01*
X829552Y129111D01*
X823879Y125285D01*
Y125284D01*
X799702Y108976D01*
X779034Y95035D01*
Y95034D01*
X764148Y92063D01*
X756348D01*
X755785Y91500D01*
G01X815911Y292500D02*
X838736D01*
X855358Y275878D01*
X862748Y238917D01*
X846981Y157811D01*
X842937Y151817D01*
Y151816D01*
X841465Y151530D01*
X840643Y150311D01*
X840929Y148839D01*
X840107Y147621D01*
X838636Y147335D01*
X837814Y146116D01*
X838100Y144645D01*
X837277Y143426D01*
X835806Y143140D01*
X834984Y141921D01*
X835270Y140450D01*
X828399Y130264D01*
X822985Y126612D01*
X821514Y126898D01*
X820295Y126076D01*
X820009Y124605D01*
X818791Y123783D01*
X817319Y124069D01*
X816100Y123247D01*
X815814Y121775D01*
X814596Y120953D01*
X813124Y121239D01*
X811905Y120417D01*
X811619Y118946D01*
X798808Y110304D01*
X797337Y110590D01*
X796118Y109768D01*
X795832Y108296D01*
X794613Y107474D01*
X793142Y107760D01*
X791923Y106938D01*
X791637Y105467D01*
X790418Y104645D01*
X788947Y104931D01*
X787728Y104109D01*
X787442Y102637D01*
X786224Y101815D01*
X784752Y102101D01*
X783533Y101279D01*
X783247Y99807D01*
X778405Y96541D01*
X763989Y93663D01*
X756122D01*
X755785Y94000D01*
G01X755784Y99500D02*
X756359Y100075D01*
X764324D01*
X772108Y101588D01*
X821559Y134941D01*
X828296Y139486D01*
X843927Y162664D01*
X858805Y239217D01*
X853026Y268973D01*
X834009Y287990D01*
X809320D01*
X806500Y285170D01*
X805740D01*
G01X755784Y102000D02*
X756109Y101675D01*
X764169D01*
X771483Y103097D01*
X771482Y103098D01*
X778107Y107565D01*
X778393Y109036D01*
X779612Y109858D01*
X781083Y109572D01*
X782302Y110394D01*
X782588Y111866D01*
X783807Y112688D01*
X785278Y112402D01*
X786497Y113224D01*
X786783Y114695D01*
X788002Y115517D01*
X789472Y115231D01*
X789473D01*
X809847Y128973D01*
X810133Y130444D01*
X811351Y131266D01*
X812823Y130980D01*
X814042Y131802D01*
X814328Y133274D01*
X815546Y134096D01*
X817018Y133810D01*
X818237Y134632D01*
X818523Y136103D01*
X819741Y136925D01*
X821213Y136639D01*
X827143Y140639D01*
X842418Y163289D01*
X857175Y239217D01*
X851548Y268187D01*
X833346Y286390D01*
X809983D01*
X807163Y283570D01*
X805740D01*
G54D77*
G01X120350Y490210D02*
X118890D01*
X117200Y491900D01*
Y495200D01*
G01X207500Y499130D02*
Y503000D01*
G01Y495630D02*
X208560D01*
X210660Y497730D01*
X214040D01*
G01X170838Y481762D02*
Y478738D01*
X167893Y475793D01*
X165382D01*
G01X314150Y514560D02*
X310410D01*
X310100Y514250D01*
G01X321800Y678500D02*
Y678250D01*
X324259Y675791D01*
X326289D01*
X326300Y675780D01*
G01X321750Y681900D02*
Y678550D01*
X321800Y678500D01*
G01X356600Y524350D02*
X357650D01*
X359540Y522460D01*
X362850D01*
G01X364500Y525260D02*
X363760Y526000D01*
X358250D01*
X356600Y524350D01*
G01X358430Y534960D02*
X359250Y535780D01*
Y541100D01*
X359550Y541400D01*
G01X358430Y534960D02*
X358152D01*
X355312Y537800D01*
X349900D01*
X347900Y539800D01*
G01X360970Y689440D02*
X368190D01*
X368250Y689500D01*
G01X361070Y702040D02*
X367510D01*
X367600Y701950D01*
G01X609750Y358900D02*
X609500Y359150D01*
X604059D01*
G01X755906Y221654D02*
X759000Y218560D01*
Y218350D01*
G54D68*
X622025Y211250D03*
X623995D03*
X625960D03*
X627930D03*
X629900D03*
X631870D03*
X633835D03*
X635805D03*
X637775D03*
X639740D03*
X641710D03*
X643680D03*
X645645D03*
X647615D03*
X649585D03*
X651555D03*
X653520D03*
X655490D03*
X657460D03*
X659425D03*
X661395D03*
X663365D03*
X665330D03*
X667300D03*
Y286950D03*
X665330D03*
X663365D03*
X661395D03*
X659425D03*
X657460D03*
X655490D03*
X653520D03*
X651555D03*
X649585D03*
X647615D03*
X645645D03*
X643680D03*
X641710D03*
X639740D03*
X637775D03*
X635805D03*
X633835D03*
X631870D03*
X629900D03*
X627930D03*
X625960D03*
X623995D03*
X622025D03*
X669270Y211250D03*
X671240D03*
X673205D03*
X675175D03*
Y286950D03*
X673205D03*
X671240D03*
X669270D03*
G54D59*
X466550Y61800D03*
X474050Y65675D03*
Y57925D03*
G54D87*
G01X777952Y290944D02*
X777401D01*
X776426Y291919D01*
Y294751D01*
X777289Y295614D01*
Y298215D01*
X778825Y299751D01*
Y300626D01*
X778575Y300876D01*
Y300969D01*
G01X777989Y294093D02*
X778014Y294118D01*
Y297914D01*
X779550Y299450D01*
Y300626D01*
X779800Y300876D01*
Y300969D01*
G01X774802Y290944D02*
X773247Y292499D01*
Y294746D01*
X774110Y295609D01*
Y297587D01*
X774410Y297887D01*
Y301932D01*
X774160Y302182D01*
Y302275D01*
G01X774835Y294088D02*
Y297286D01*
X775135Y297586D01*
Y301932D01*
X775385Y302182D01*
Y302275D01*
G01X768503Y290944D02*
X766913Y293598D01*
Y301161D01*
X766575Y301499D01*
Y305657D01*
X766325Y305907D01*
Y306000D01*
G01X768498Y294124D02*
X767638Y294984D01*
Y301462D01*
X767300Y301800D01*
Y305657D01*
X767550Y305907D01*
Y306000D01*
G01X765353Y290944D02*
X763736Y292561D01*
Y294741D01*
X763950Y294955D01*
Y298950D01*
X763410Y299490D01*
Y301332D01*
X763160Y301582D01*
Y301675D01*
G01X765325Y294102D02*
X764675Y294752D01*
Y299251D01*
X764135Y299791D01*
Y301332D01*
X764385Y301582D01*
Y301675D01*
G01X759054Y290944D02*
X757492Y293422D01*
Y295178D01*
X756147Y297199D01*
Y305327D01*
X755528Y305946D01*
X755174D01*
X755108Y306012D01*
G01X759055Y294094D02*
X758217Y294932D01*
Y295398D01*
X756872Y297419D01*
Y305628D01*
X756041Y306459D01*
Y306813D01*
X755975Y306879D01*
G01X755905Y290944D02*
Y291639D01*
G03X755794Y291905I-374J0D01*
G01X755724Y291975D01*
G03X755289Y292156I-436J-435D01*
G01X753318D01*
X752522Y292952D01*
Y295048D01*
X753410Y295936D01*
Y298282D01*
X753160Y298532D01*
Y298625D01*
G01X755905Y294093D02*
Y293442D01*
G02X755795Y293176I-375J-1D01*
G01X755702Y293084D01*
G02X755214Y292881I-489J488D01*
G01X753619D01*
X753247Y293253D01*
Y294747D01*
X754135Y295635D01*
Y298282D01*
X754385Y298532D01*
Y298625D01*
G01X787500Y302100D02*
X787434Y302034D01*
Y301680D01*
X785008Y299254D01*
Y296117D01*
X785850Y295275D01*
Y292495D01*
X787401Y290944D01*
G01X788367Y301234D02*
X788301Y301168D01*
X787948D01*
X785733Y298953D01*
Y296418D01*
X786832Y295319D01*
X787408Y294074D01*
G01X784251Y290944D02*
X782650Y292545D01*
Y294752D01*
X783150Y295252D01*
Y301650D01*
X783363Y301863D01*
X785409Y303905D01*
Y304259D01*
X785475Y304325D01*
G01X784258Y294064D02*
X783875Y294397D01*
Y301349D01*
X785921Y303391D01*
X785922Y303392D01*
X786275D01*
X786341Y303458D01*
G54D78*
G01X152332Y583318D02*
X150951Y584699D01*
X146750D01*
G01X154650Y572940D02*
X164100D01*
G01X169625Y575114D02*
X155198D01*
X154150Y576162D01*
Y581500D01*
X152332Y583318D01*
G01X164100Y572940D02*
X169760D01*
X171834Y570866D01*
X172047D01*
G01X732570Y288150D02*
X732550Y288170D01*
Y289637D01*
X733857Y290944D01*
G01X736070Y288150D02*
X737007Y289087D01*
Y290944D01*
G01X743610Y287810D02*
Y290640D01*
X743306Y290944D01*
G54D69*
X689500Y305900D03*
Y308100D03*
X692000Y305900D03*
Y308100D03*
X774350Y255250D03*
Y257450D03*
X791617Y318400D03*
Y320600D03*
X793817Y318400D03*
Y320600D03*
X788817Y318400D03*
Y320600D03*
X740117Y318400D03*
Y320600D03*
X742317Y318400D03*
Y320600D03*
X746617Y318400D03*
Y320600D03*
X748817Y318400D03*
Y320600D03*
X754617Y318400D03*
Y320600D03*
X756817Y318400D03*
Y320600D03*
X759617Y318400D03*
Y320600D03*
X761817Y318400D03*
Y320600D03*
X776617Y318400D03*
Y320600D03*
X778817Y318400D03*
Y320600D03*
X781617Y318400D03*
Y320600D03*
X783817Y318400D03*
Y320600D03*
X786617Y318400D03*
Y320600D03*
X777700Y307300D03*
Y309500D03*
G54D88*
G01X786617Y320600D02*
X787137Y321120D01*
G01X759618Y318400D02*
X759617D01*
G54D79*
G01X376342Y711260D02*
X382370D01*
G01X580250Y64940D02*
X588689D01*
X588749Y65000D01*
G01X551250Y75060D02*
X545840D01*
X545300Y75600D01*
G01X573750Y70060D02*
X570495D01*
X570435Y70000D01*
X568000D01*
G54D89*
G01X471260Y174016D02*
Y172763D01*
G03X471521Y172133I891J0D01*
G03X472149Y171873I628J628D01*
G01X473047D01*
G02X476955Y167965I0J-3908D01*
G01Y111526D01*
X452571Y87142D01*
X399518D01*
X354786Y116968D01*
X351776Y127650D01*
X352477Y131252D01*
X341562Y187411D01*
Y187413D01*
X341563D01*
X345519Y207631D01*
X337465Y249072D01*
X339233Y258172D01*
X338234Y263302D01*
X335887Y265649D01*
X332765D01*
X328345Y261229D01*
X309021D01*
X305441Y257649D01*
X302774D01*
X300719Y259704D01*
Y266118D01*
X302011Y267410D01*
X303093D01*
G03X304231Y268548I0J1138D01*
G01Y265048D02*
G03X303094Y266185I-1137J0D01*
G01X302519D01*
X301944Y265610D01*
Y260212D01*
X303282Y258874D01*
X304933D01*
X308513Y262454D01*
X310238D01*
X310838Y263054D01*
X312563D01*
X313163Y262454D01*
X314888D01*
X315488Y263054D01*
X317213D01*
X317813Y262454D01*
X327837D01*
X332257Y266874D01*
X336395D01*
X339366Y263904D01*
X339879Y261267D01*
X340482Y258172D01*
X338713Y249071D01*
X339317Y245964D01*
X340021Y245489D01*
X340350Y243796D01*
X339875Y243092D01*
X340204Y241399D01*
X340908Y240925D01*
X341237Y239231D01*
X340762Y238528D01*
X341091Y236835D01*
X341795Y236360D01*
X342124Y234667D01*
X341650Y233963D01*
X341979Y232270D01*
X342682Y231795D01*
X343011Y230102D01*
X342537Y229399D01*
X346768Y207630D01*
X345491Y201101D01*
X345964Y200397D01*
X345633Y198704D01*
X344929Y198231D01*
X344598Y196538D01*
X345071Y195834D01*
X344740Y194141D01*
X344036Y193667D01*
X342811Y187410D01*
X353725Y131252D01*
X353035Y127702D01*
X355843Y117737D01*
X399889Y88367D01*
X403023D01*
X403623Y88967D01*
X405348D01*
X405948Y88367D01*
X407673D01*
X408273Y88967D01*
X409998D01*
X410598Y88367D01*
X412323D01*
X412923Y88967D01*
X414648D01*
X415248Y88367D01*
X416973D01*
X417573Y88967D01*
X419298D01*
X419898Y88367D01*
X452063D01*
X457012Y93316D01*
Y94165D01*
X458232Y95385D01*
X459081D01*
X460300Y96604D01*
Y97453D01*
X461520Y98673D01*
X462369D01*
X463588Y99892D01*
Y100741D01*
X464808Y101961D01*
X465657D01*
X466876Y103180D01*
Y104029D01*
X468096Y105249D01*
X468945D01*
X475730Y112034D01*
Y167965D01*
G03X473047Y170648I-2683J0D01*
G01X471935D01*
G03X471457Y170450I0J-676D01*
G03X471260Y169974I477J-476D01*
G01Y168504D01*
G01Y131496D02*
Y130026D01*
G02X471063Y129550I-674J0D01*
G02X470585Y129352I-478J478D01*
G01X469473D01*
G03X467104Y126983I0J-2369D01*
G01Y112757D01*
X448493Y94146D01*
X400420D01*
X360345Y120867D01*
X358588Y126894D01*
X358504Y127310D01*
X359318Y131022D01*
X350865Y173373D01*
X353740Y187748D01*
X352509Y194036D01*
X352173Y195750D01*
X351939Y196944D01*
X351370Y199850D01*
X352686Y206619D01*
X345142Y246268D01*
X345838Y250784D01*
X345501Y252557D01*
X345203Y254121D01*
Y254122D01*
X346115Y260039D01*
X343722Y270031D01*
X336256Y277497D01*
X329759D01*
X324608Y282648D01*
X320323D01*
X317629Y279954D01*
X308582D01*
G02X307567Y280969I0J1015D01*
G01Y281092D01*
G01X471260Y125985D02*
Y127237D01*
G03X470999Y127867I-891J0D01*
G03X470371Y128127I-628J-628D01*
G01X469473D01*
G03X468329Y126983I0J-1144D01*
G01Y112249D01*
X449001Y92921D01*
X400049D01*
X359294Y120095D01*
X357397Y126601D01*
X357252Y127320D01*
X358066Y131034D01*
X349615Y173373D01*
X352491Y187751D01*
X350970Y195515D01*
X350926Y195739D01*
X350852Y196112D01*
X350736Y196709D01*
X350121Y199849D01*
X351438Y206621D01*
X343899Y246246D01*
X344595Y250762D01*
X344315Y252233D01*
X344314D01*
X344297Y252328D01*
X344148Y253110D01*
X343960Y254098D01*
X343959D01*
X344867Y259988D01*
X342611Y269409D01*
X335748Y276272D01*
X329251D01*
X324100Y281423D01*
X320831D01*
X318137Y278729D01*
X308582D01*
G03X307567Y277714I0J-1015D01*
G01Y277592D01*
G01X464173Y136221D02*
Y134751D01*
G02X463976Y134275I-674J0D01*
G02X463498Y134077I-478J478D01*
G01X462386D01*
G03X460017Y131708I0J-2369D01*
G01Y119480D01*
X439472Y98935D01*
X405596D01*
X373341Y120447D01*
X363256Y135574D01*
X355724Y173310D01*
X357532Y182351D01*
X358535Y187374D01*
X356134Y199555D01*
X357795Y207856D01*
X350462Y244482D01*
X353385Y255018D01*
X350201Y270936D01*
X347001Y286932D01*
X339484Y294449D01*
X332898D01*
X328275Y289826D01*
X320930D01*
X318202Y292554D01*
X305182D01*
G02X304267Y293469I0J915D01*
G01Y293692D01*
G01X464173Y130709D02*
Y131962D01*
G03X463912Y132592I-891J0D01*
G03X463284Y132852I-628J-628D01*
G01X462386D01*
G03X461242Y131708I0J-1144D01*
G01Y118972D01*
X439980Y97710D01*
X405224D01*
X372457Y119563D01*
X367278Y127332D01*
X364757Y131114D01*
X362102Y135096D01*
X354474Y173310D01*
X354521Y173550D01*
X354522D01*
X355928Y180582D01*
X357286Y187376D01*
X357285D01*
X356696Y190361D01*
X356697D01*
X354885Y199557D01*
X356545Y207856D01*
X349203Y244528D01*
X352126Y255064D01*
X350562Y262881D01*
X350561D01*
X345872Y286328D01*
X338976Y293224D01*
X333406D01*
X328783Y288601D01*
X320422D01*
X317694Y291329D01*
X305182D01*
G03X304267Y290414I0J-915D01*
G01Y290192D01*
G01X457086Y131496D02*
Y130026D01*
G02X456889Y129550I-674J0D01*
G02X456411Y129352I-478J478D01*
G01X455299D01*
G03X452930Y126983I0J-2369D01*
G01Y119313D01*
X438603Y104986D01*
X407692D01*
X379087Y124282D01*
X366478Y143106D01*
X360495Y172997D01*
X364565Y192151D01*
X365207Y195177D01*
X363599Y202727D01*
X363951Y204380D01*
X355877Y242438D01*
X357083Y246783D01*
X357651Y248831D01*
X358073Y250354D01*
X358573Y252156D01*
X349795Y296038D01*
X342671Y303162D01*
X333395D01*
X329021Y307536D01*
X320611D01*
X318229Y305154D01*
X308705D01*
G02X307567Y306292I0J1138D01*
G01X457086Y125985D02*
Y127237D01*
G03X456825Y127867I-891J0D01*
G03X456197Y128127I-628J-628D01*
G01X455299D01*
G03X454155Y126983I0J-1144D01*
G01Y118805D01*
X439111Y103761D01*
X407317D01*
X378202Y123400D01*
X365324Y142626D01*
X359244Y173004D01*
X359296Y173251D01*
X361598Y184090D01*
X362776Y189634D01*
X362777Y189635D01*
X363954Y195177D01*
X362346Y202727D01*
X362698Y204380D01*
X354616Y242477D01*
X355902Y247111D01*
X356470Y249159D01*
X357314Y252202D01*
X348666Y295434D01*
X342163Y301937D01*
X332887D01*
X328513Y306311D01*
X321119D01*
X318737Y303929D01*
X308704D01*
G03X307567Y302792I0J-1137D01*
G01X450000Y136221D02*
Y134751D01*
G02X449803Y134275I-674J0D01*
G02X449325Y134077I-478J478D01*
G01X448213D01*
G03X445844Y131708I0J-2369D01*
G01Y119452D01*
X435878Y109486D01*
X413158D01*
X380992Y130959D01*
X370320Y146892D01*
X365382Y171566D01*
X370296Y196122D01*
X368642Y204378D01*
X370728Y214863D01*
X351838Y309295D01*
X341514Y319619D01*
X333073D01*
X328208Y314754D01*
X320702D01*
X317702Y317754D01*
X305082D01*
G02X304267Y318569I0J815D01*
G01Y318892D01*
G01X450000Y130709D02*
Y131962D01*
G03X449739Y132592I-891J0D01*
G03X449111Y132852I-628J-628D01*
G01X448213D01*
G03X447069Y131708I0J-1144D01*
G01Y118944D01*
X436386Y108261D01*
X412786D01*
X380109Y130074D01*
X379973Y130277D01*
X379974D01*
X374638Y138244D01*
X369166Y146412D01*
X364132Y171566D01*
X364180Y171806D01*
X366613Y183965D01*
X369046Y196122D01*
X367392Y204377D01*
X369478Y214862D01*
X350709Y308691D01*
X341006Y318394D01*
X333581D01*
X328716Y313529D01*
X320194D01*
X317194Y316529D01*
X305082D01*
G03X304267Y315714I0J-815D01*
G01Y315392D01*
G01X442913Y131496D02*
Y130026D01*
G02X442716Y129550I-674J0D01*
G02X442238Y129352I-478J478D01*
G01X441126D01*
G03X438757Y126983I0J-2369D01*
G01Y121269D01*
X431474Y113986D01*
X415548D01*
X385228Y134200D01*
X377905Y145195D01*
X372237Y173490D01*
X377938Y201951D01*
X355747Y312886D01*
X340881Y327752D01*
X334161D01*
X328041Y333872D01*
X320847D01*
X318566Y331590D01*
X317430Y330454D01*
X308705D01*
G02X307567Y331592I0J1138D01*
G01X442913Y125985D02*
Y127237D01*
G03X442652Y127867I-891J0D01*
G03X442024Y128127I-628J-628D01*
G01X441126D01*
G03X439982Y126983I0J-1144D01*
G01Y120761D01*
X431982Y112761D01*
X415177D01*
X384344Y133317D01*
X376751Y144717D01*
X370987Y173490D01*
X376688Y201951D01*
X354618Y312282D01*
X340373Y326527D01*
X333653D01*
X327533Y332647D01*
X321355D01*
X319433Y330723D01*
X317938Y329229D01*
X308704D01*
G03X307567Y328092I0J-1137D01*
G01X435827Y136221D02*
Y134751D01*
G02X435630Y134275I-674J0D01*
G02X435152Y134077I-478J478D01*
G01X434040D01*
G03X431671Y131708I0J-2369D01*
G01Y120549D01*
X429608Y118486D01*
X417573D01*
X389540Y137073D01*
X382093Y148114D01*
X376956Y173811D01*
X382581Y201925D01*
X359735Y316155D01*
X343990Y339343D01*
X338134Y345199D01*
X333623D01*
X328499Y340075D01*
X320581D01*
X317702Y342954D01*
X305405D01*
G02X304267Y344092I0J1138D01*
G01X435827Y130709D02*
Y131962D01*
G03X435566Y132592I-891J0D01*
G03X434938Y132852I-628J-628D01*
G01X434040D01*
G03X432896Y131708I0J-1144D01*
G01Y120041D01*
X430116Y117261D01*
X417203D01*
X388660Y136186D01*
X380939Y147632D01*
X375706Y173811D01*
X381331Y201925D01*
X358582Y315672D01*
X343040Y338560D01*
X337626Y343974D01*
X334131D01*
X329007Y338850D01*
X320073D01*
X317194Y341729D01*
X305404D01*
G03X304267Y340592I0J-1137D01*
G01X428740Y131496D02*
Y130026D01*
G02X428543Y129550I-674J0D01*
G02X428065Y129352I-478J478D01*
G01X426953D01*
G03X424584Y126983I0J-2369D01*
G01Y124567D01*
X423090Y123073D01*
X420520D01*
X418215Y123532D01*
X393234Y140134D01*
X386443Y150197D01*
X381750Y174328D01*
X384848Y189785D01*
X388042Y205720D01*
X366231Y314762D01*
X344221Y347779D01*
X340001Y351999D01*
X334857D01*
X328890Y357966D01*
X320141D01*
X317729Y355554D01*
X308705D01*
G02X307567Y356692I0J1138D01*
G01X428740Y125985D02*
Y127237D01*
G03X428479Y127867I-891J0D01*
G03X427851Y128127I-628J-628D01*
G01X426953D01*
G03X425809Y126983I0J-1144D01*
G01Y124059D01*
X423598Y121848D01*
X420399D01*
X417738Y122377D01*
X392353Y139247D01*
X385288Y149718D01*
X380500Y174332D01*
X386792Y205720D01*
X365077Y314284D01*
X343268Y346999D01*
X339493Y350774D01*
X334349D01*
X328382Y356741D01*
X320649D01*
X318237Y354329D01*
X308704D01*
G03X307567Y353192I0J-1137D01*
G01X421653Y136221D02*
Y134932D01*
G02X421402Y134328I-855J1D01*
G01X421321Y134246D01*
G02X420913Y134077I-407J406D01*
G01X415815D01*
X410629Y135115D01*
X395485Y145211D01*
X394458Y146742D01*
X391450Y161810D01*
X389948Y169343D01*
X389947Y169344D01*
X388913Y174524D01*
X388819Y174995D01*
X388444Y176875D01*
X393639Y202856D01*
X371070Y315703D01*
X352909Y342950D01*
X349730Y356360D01*
X336103Y369987D01*
X333334D01*
X327764Y364417D01*
X321439D01*
X317702Y368154D01*
X305182D01*
G02X304267Y369069I0J915D01*
G01Y369292D01*
G01X421653Y130709D02*
Y132233D01*
G03X421472Y132670I-618J0D01*
G03X421033Y132852I-439J-438D01*
G01X415693D01*
X410151Y133961D01*
X394602Y144326D01*
X393304Y146262D01*
X388369Y170987D01*
X387993Y172870D01*
X387194Y176875D01*
X392389Y202856D01*
X369916Y315225D01*
X351767Y342453D01*
X348618Y355739D01*
X335595Y368762D01*
X333842D01*
X328272Y363192D01*
X320931D01*
X317194Y366929D01*
X305182D01*
G03X304267Y366014I0J-915D01*
G01Y365792D01*
G01X386733Y424903D02*
Y367123D01*
X378067Y358457D01*
X367696D01*
X357663Y348424D01*
Y343239D01*
X397675Y303227D01*
Y168857D01*
X395596Y166778D01*
Y161005D01*
X397089Y159512D01*
X398902D01*
X400205Y158209D01*
G01X387958Y436223D02*
Y366615D01*
X378575Y357232D01*
X368204D01*
X358888Y347916D01*
Y343747D01*
X372854Y329781D01*
X373703D01*
X374922Y328561D01*
Y327713D01*
X376142Y326493D01*
X376991D01*
X378210Y325273D01*
Y324425D01*
X379430Y323205D01*
X380279D01*
X381498Y321985D01*
Y321137D01*
X382718Y319917D01*
X383567D01*
X384787Y318697D01*
Y317848D01*
X398900Y303735D01*
Y168349D01*
X396821Y166270D01*
Y161513D01*
X397597Y160737D01*
X399036D01*
X400205Y161906D01*
G01X384158Y638105D02*
X383000Y639263D01*
Y642294D01*
X383948Y643242D01*
X387629D01*
X389750Y641121D01*
Y620768D01*
X386992Y618010D01*
Y610172D01*
X388446Y608718D01*
Y579514D01*
X390387Y577573D01*
Y551646D01*
X392875Y549158D01*
Y507882D01*
X390420Y505427D01*
Y492863D01*
X381378Y483821D01*
Y455092D01*
X386733Y449737D01*
Y424903D01*
G01D02*
X385673D01*
G01X380443Y638105D02*
X381775Y639437D01*
Y642802D01*
X383440Y644467D01*
X388137D01*
X390975Y641629D01*
Y620260D01*
X388217Y617502D01*
Y610680D01*
X389671Y609226D01*
Y580022D01*
X391612Y578081D01*
Y552154D01*
X394100Y549666D01*
Y507374D01*
X391645Y504919D01*
Y492355D01*
X382603Y483313D01*
Y455600D01*
X387958Y450245D01*
Y436223D01*
G01D02*
X389151D01*
G01X535039Y150394D02*
Y148924D01*
G02X534842Y148448I-674J0D01*
G02X534364Y148250I-478J478D01*
G01X533252D01*
G03X530883Y145881I0J-2369D01*
G01Y115660D01*
X542009Y104534D01*
X568951D01*
X576316Y109443D01*
X585735Y123577D01*
X597856Y184239D01*
X588148Y232799D01*
X600799Y296028D01*
X604432Y301475D01*
X672776Y347039D01*
X727426Y357967D01*
X739885Y355476D01*
X755844Y344838D01*
X777093Y323589D01*
Y321076D01*
X776617Y320600D01*
G01X535039Y144882D02*
Y146135D01*
G03X534778Y146765I-891J0D01*
G03X534150Y147025I-628J-628D01*
G01X533252D01*
G03X532108Y145881I0J-1144D01*
G01Y116168D01*
X533328Y114948D01*
X534176D01*
X535396Y113728D01*
Y112880D01*
X542517Y105759D01*
X568580D01*
X575432Y110327D01*
X576750Y112305D01*
X577465Y113378D01*
X584581Y124055D01*
X596606Y184239D01*
X586898Y232799D01*
X593272Y264654D01*
X599645Y296506D01*
X603548Y302359D01*
X672298Y348193D01*
X673386Y348411D01*
X675945Y348922D01*
X676416Y349628D01*
X678108Y349967D01*
X678814Y349496D01*
X680506Y349834D01*
X680976Y350540D01*
X682668Y350879D01*
X683374Y350408D01*
X685066Y350746D01*
X685536Y351452D01*
X687228Y351791D01*
X687934Y351320D01*
X709186Y355570D01*
Y355569D01*
X709657Y356275D01*
X711348Y356613D01*
X712054Y356143D01*
X713746Y356481D01*
X714217Y357187D01*
X715908Y357525D01*
X716614Y357055D01*
X718306Y357393D01*
X718777Y358099D01*
X720468Y358437D01*
X721174Y357967D01*
X722866Y358305D01*
X723337Y359011D01*
X725028Y359349D01*
X725734Y358879D01*
X727426Y359217D01*
X731243Y358454D01*
X731949Y358924D01*
X733641Y358586D01*
X734111Y357880D01*
X735803Y357542D01*
X736509Y358012D01*
X738201Y357674D01*
X738671Y356968D01*
X740363Y356630D01*
X745018Y353528D01*
X745850Y353694D01*
X747285Y352738D01*
X747452Y351906D01*
X748887Y350949D01*
X749719Y351115D01*
X751154Y350159D01*
X751321Y349327D01*
X752756Y348370D01*
X753588Y348536D01*
X755023Y347580D01*
X755190Y346748D01*
X756625Y345791D01*
X778318Y324097D01*
Y321099D01*
X778817Y320600D01*
G01X759617D02*
X760093Y321076D01*
Y329490D01*
X750388Y339195D01*
X745005Y343232D01*
X713231Y349588D01*
X672489Y341437D01*
X607909Y298383D01*
X605002Y294005D01*
X592762Y232791D01*
X602509Y184053D01*
X589960Y121294D01*
X579780Y106020D01*
X570802Y100034D01*
X539857D01*
X523797Y116094D01*
Y141157D01*
G02X526166Y143526I2369J0D01*
G01X527278D01*
G03X527756Y143724I0J676D01*
G03X527953Y144200I-477J476D01*
G01Y145670D01*
G01X761817Y320600D02*
X761318Y321099D01*
Y329998D01*
X760098Y331218D01*
Y332066D01*
X758878Y333286D01*
X758030D01*
X756810Y334506D01*
Y335354D01*
X755590Y336574D01*
X754742D01*
X751193Y340123D01*
X745518Y344379D01*
X743827Y344717D01*
X743356Y345423D01*
X741664Y345762D01*
X740958Y345291D01*
X739267Y345630D01*
X738796Y346336D01*
X737105Y346674D01*
X736399Y346203D01*
X734707Y346542D01*
X734237Y347248D01*
X732545Y347586D01*
X731839Y347116D01*
X730148Y347454D01*
X729677Y348160D01*
X727985Y348498D01*
X727279Y348028D01*
X713231Y350838D01*
X711540Y350500D01*
X710833Y350970D01*
X709142Y350632D01*
X708671Y349926D01*
X706980Y349587D01*
X706274Y350058D01*
X704582Y349720D01*
X704112Y349013D01*
X702420Y348675D01*
X701714Y349146D01*
X700023Y348807D01*
X699552Y348101D01*
X697861Y347763D01*
X697155Y348233D01*
X695463Y347895D01*
X694992Y347189D01*
X693301Y346851D01*
X692594Y347321D01*
X690903Y346983D01*
X690432Y346277D01*
X672011Y342591D01*
X607024Y299266D01*
X603848Y294482D01*
X591512Y232791D01*
X601259Y184053D01*
X588806Y121772D01*
X578896Y106904D01*
X570431Y101259D01*
X540365D01*
X525022Y116602D01*
Y141157D01*
G02X526166Y142301I1144J0D01*
G01X527064D01*
G02X527692Y142041I0J-888D01*
G02X527953Y141411I-630J-630D01*
G01Y140158D01*
G01X754617Y320600D02*
X755075Y321058D01*
Y328108D01*
X748141Y335041D01*
X742310Y338929D01*
X712418Y344805D01*
X674186Y337158D01*
X611526Y295384D01*
X609168Y291850D01*
X597535Y233630D01*
X607599Y183277D01*
Y183275D01*
X594754Y119022D01*
X584323Y103376D01*
X572379Y95414D01*
X537671D01*
X516710Y116375D01*
Y145881D01*
G02X519079Y148250I2369J0D01*
G01X520191D01*
G03X520669Y148448I0J676D01*
G03X520866Y148924I-477J476D01*
G01Y150394D01*
G01X756817Y320600D02*
X756300Y321117D01*
Y328616D01*
X748922Y335994D01*
X742786Y340084D01*
X712416Y346054D01*
X673708Y338312D01*
X610642Y296268D01*
X608014Y292328D01*
X596285Y233630D01*
X606348Y183281D01*
Y183279D01*
X606010Y181587D01*
X605304Y181117D01*
X604966Y179425D01*
X605437Y178719D01*
X605099Y177028D01*
X604393Y176557D01*
X604054Y174865D01*
X604525Y174159D01*
X604187Y172468D01*
X603481Y171997D01*
X603143Y170306D01*
X603614Y169600D01*
X603276Y167908D01*
X602570Y167437D01*
X602232Y165746D01*
X602702Y165040D01*
X602364Y163348D01*
X601658Y162878D01*
X601320Y161186D01*
X601791Y160480D01*
X597246Y137739D01*
X596540Y137268D01*
X596201Y135577D01*
X596672Y134871D01*
X596334Y133179D01*
X595628Y132709D01*
X595290Y131017D01*
X595761Y130311D01*
X595423Y128620D01*
X594717Y128149D01*
X594379Y126457D01*
X594849Y125751D01*
X594511Y124060D01*
X593805Y123589D01*
X593467Y121898D01*
X593938Y121192D01*
X593600Y119500D01*
X591178Y115867D01*
X590346Y115700D01*
X589389Y114265D01*
X589555Y113433D01*
X588598Y111998D01*
X587766Y111831D01*
X586809Y110396D01*
X586975Y109564D01*
X586019Y108129D01*
X585186Y107963D01*
X584230Y106527D01*
X584396Y105695D01*
X583439Y104260D01*
X572008Y96639D01*
X538179D01*
X517935Y116883D01*
Y145881D01*
G02X519079Y147025I1144J0D01*
G01X519977D01*
G02X520605Y146765I0J-888D01*
G02X520866Y146135I-630J-630D01*
G01Y144882D01*
G01X746617Y320600D02*
X747093Y321076D01*
Y323990D01*
X740859Y330223D01*
X733004Y335460D01*
Y335459D01*
X733003Y335460D01*
X710843Y339892D01*
X675925Y332907D01*
X615235Y292445D01*
X613390Y289710D01*
X602738Y234912D01*
X612949Y183843D01*
X599802Y118109D01*
X587344Y99638D01*
X574181Y90760D01*
X535844D01*
X509623Y116981D01*
Y141157D01*
G02X511992Y143526I2369J0D01*
G01X513104D01*
G03X513582Y143724I0J676D01*
G03X513779Y144200I-477J476D01*
G01Y145670D01*
G01X748817Y320600D02*
X748318Y321099D01*
Y324498D01*
X741640Y331176D01*
X733482Y336614D01*
X710843Y341142D01*
X675447Y334061D01*
X614354Y293331D01*
X612234Y290189D01*
X601489Y234909D01*
X601827Y233217D01*
X601356Y232511D01*
X601695Y230820D01*
X602401Y230349D01*
X602739Y228658D01*
X602268Y227952D01*
X602606Y226260D01*
X603312Y225789D01*
X603650Y224097D01*
X603179Y223391D01*
X603518Y221700D01*
X604224Y221229D01*
X608052Y202082D01*
X607582Y201376D01*
X607920Y199685D01*
X608626Y199214D01*
X608964Y197522D01*
X608493Y196816D01*
X608832Y195125D01*
X609538Y194654D01*
X609876Y192963D01*
X609405Y192257D01*
X609743Y190565D01*
X610449Y190094D01*
X610787Y188403D01*
X610317Y187697D01*
X610655Y186005D01*
X611361Y185535D01*
X611699Y183843D01*
X602296Y136830D01*
X601590Y136359D01*
X601251Y134668D01*
X601722Y133962D01*
X601384Y132270D01*
X600678Y131799D01*
X600340Y130108D01*
X600810Y129402D01*
X600472Y127710D01*
X599766Y127240D01*
X599428Y125548D01*
X599898Y124842D01*
X599560Y123151D01*
X598854Y122680D01*
X598516Y120989D01*
X598986Y120283D01*
X598648Y118591D01*
X586461Y100521D01*
X573806Y91985D01*
X536352D01*
X510848Y117489D01*
Y141157D01*
G02X511992Y142301I1144J0D01*
G01X512890D01*
G02X513518Y142041I0J-888D01*
G02X513779Y141411I-630J-630D01*
G01Y140158D01*
G01X740117Y320600D02*
X740618Y321101D01*
Y323230D01*
X737359Y326488D01*
X729900Y331462D01*
X710823Y335276D01*
X677635Y328637D01*
X619328Y289763D01*
X617648Y287272D01*
X607729Y236247D01*
X617888Y185282D01*
X604101Y116357D01*
X590220Y95534D01*
X575917Y86000D01*
X567500D01*
X566375Y84875D01*
X556757D01*
X555372Y86260D01*
X533979D01*
X502537Y117702D01*
Y145881D01*
G02X504906Y148250I2369J0D01*
G01X506018D01*
G03X506496Y148448I0J676D01*
G03X506693Y148924I-477J476D01*
G01Y150394D01*
G01X742317Y320600D02*
X741843Y321074D01*
Y323738D01*
X738140Y327441D01*
X730378Y332616D01*
X710823Y336526D01*
X677157Y329791D01*
X618447Y290648D01*
X616492Y287751D01*
X606480Y236244D01*
X606817Y234552D01*
X606346Y233847D01*
X606683Y232155D01*
X607389Y231684D01*
X607726Y229992D01*
X607255Y229286D01*
X607592Y227595D01*
X608298Y227123D01*
X608635Y225431D01*
X608164Y224726D01*
X608501Y223034D01*
X609207Y222563D01*
X613002Y203523D01*
X612531Y202817D01*
X612868Y201126D01*
X613574Y200655D01*
X613911Y198963D01*
X613440Y198257D01*
X613777Y196565D01*
X614483Y196094D01*
X614820Y194403D01*
X614349Y193697D01*
X614686Y192005D01*
X615392Y191534D01*
X615729Y189842D01*
X615258Y189137D01*
X615595Y187445D01*
X616301Y186974D01*
X616638Y185282D01*
X602947Y116835D01*
X589336Y96418D01*
X575546Y87225D01*
X566992D01*
X565867Y86100D01*
X557265D01*
X555880Y87485D01*
X534487D01*
X503762Y118210D01*
Y145881D01*
G02X504906Y147025I1144J0D01*
G01X505804D01*
G02X506432Y146765I0J-888D01*
G02X506693Y146135I-630J-630D01*
G01Y144882D01*
G01X781617Y320600D02*
X781618D01*
X782101Y321083D01*
Y325166D01*
X755800Y351467D01*
X737548Y363637D01*
X721977Y366750D01*
X682349Y358824D01*
X601210Y304916D01*
X596443Y297768D01*
X583452Y232794D01*
X593199Y184076D01*
X581388Y125731D01*
X574294Y115092D01*
X565214Y109034D01*
X547969D01*
X537970Y119033D01*
Y141157D01*
G02X540339Y143526I2369J0D01*
G01X541451D01*
G03X541929Y143724I0J676D01*
G03X542126Y144200I-477J476D01*
G01Y145670D01*
G01Y140158D02*
Y141411D01*
G03X541865Y142041I-891J0D01*
G03X541237Y142301I-628J-628D01*
G01X540339D01*
G03X539195Y141157I0J-1144D01*
G01Y119541D01*
X548477Y110259D01*
X564842D01*
X573410Y115976D01*
X574367Y117411D01*
X574201Y118243D01*
X575158Y119678D01*
X575990Y119845D01*
X576947Y121280D01*
X576781Y122112D01*
X577738Y123547D01*
X578570Y123714D01*
X580234Y126211D01*
X580576Y127902D01*
X580107Y128609D01*
X580450Y130300D01*
X581157Y130769D01*
X581499Y132460D01*
X581030Y133167D01*
X581372Y134858D01*
X582080Y135327D01*
X582422Y137018D01*
X581953Y137725D01*
X582295Y139416D01*
X583003Y139885D01*
X583345Y141576D01*
X582876Y142283D01*
X583218Y143974D01*
X583926Y144443D01*
X583925D01*
X588258Y165847D01*
X587789Y166554D01*
X588132Y168245D01*
X588839Y168714D01*
X589181Y170404D01*
X588712Y171112D01*
X589054Y172802D01*
X589761Y173271D01*
X590104Y174962D01*
X589635Y175669D01*
X589977Y177360D01*
X590684Y177829D01*
X591026Y179519D01*
X590557Y180227D01*
X590900Y181917D01*
X591607Y182386D01*
X591949Y184077D01*
X582202Y232794D01*
X588745Y265521D01*
X595289Y298246D01*
X600327Y305801D01*
X681872Y359978D01*
X721977Y368000D01*
X738026Y364791D01*
X741105Y362738D01*
X741937Y362904D01*
X743373Y361947D01*
X743539Y361115D01*
X744974Y360158D01*
X745806Y360325D01*
X747241Y359368D01*
X747408Y358536D01*
X748843Y357579D01*
X749675Y357745D01*
X751110Y356788D01*
X751277Y355956D01*
X756581Y352420D01*
X783326Y325674D01*
Y321091D01*
X783817Y320600D01*
G01X556299Y145670D02*
Y144200D01*
G02X556102Y143724I-674J0D01*
G02X555624Y143526I-478J478D01*
G01X554512D01*
G03X552143Y141157I0J-2369D01*
G01Y119852D01*
X553961Y118034D01*
X561035D01*
X564957Y120681D01*
X572032Y131306D01*
X582494Y183681D01*
X574217Y232973D01*
X577203Y247889D01*
X578199Y252862D01*
Y252863D01*
X582183Y272755D01*
X588107Y302339D01*
X595710Y313063D01*
X679481Y367792D01*
X723630Y376623D01*
X744158Y372516D01*
X768439Y356329D01*
X792084Y332684D01*
Y321067D01*
X791617Y320600D01*
G01X556299Y140158D02*
Y141411D01*
G03X556038Y142041I-891J0D01*
G03X555410Y142301I-628J-628D01*
G01X554512D01*
G03X553368Y141157I0J-1144D01*
G01Y120360D01*
X554469Y119259D01*
X560660D01*
X564071Y121561D01*
X570877Y131784D01*
X570878D01*
X571216Y133476D01*
X570745Y134181D01*
X571083Y135873D01*
X571789Y136344D01*
X572127Y138036D01*
X571656Y138741D01*
X571993Y140433D01*
X572699Y140904D01*
X573037Y142596D01*
X572566Y143301D01*
X572904Y144993D01*
X573610Y145464D01*
X573948Y147155D01*
X573477Y147861D01*
X573815Y149553D01*
X574521Y150024D01*
X577604Y165462D01*
X577133Y166168D01*
X577471Y167860D01*
X578177Y168331D01*
X578515Y170022D01*
X578044Y170728D01*
X578382Y172420D01*
X579088Y172890D01*
X579426Y174582D01*
X578955Y175288D01*
X579293Y176980D01*
X579998Y177450D01*
X580336Y179142D01*
X579865Y179848D01*
X580203Y181540D01*
X580909Y182010D01*
X581247Y183702D01*
X572971Y232992D01*
X576001Y248129D01*
X576249Y249372D01*
X576498Y250616D01*
X576499D01*
X580981Y272998D01*
X586957Y302835D01*
X594845Y313962D01*
X679009Y368947D01*
X679011Y368948D01*
X723630Y377873D01*
X734134Y375773D01*
X744636Y373670D01*
X748385Y371171D01*
X749217Y371338D01*
X750652Y370381D01*
X750819Y369549D01*
X752254Y368592D01*
X753086Y368758D01*
X754521Y367801D01*
X754688Y366969D01*
X756123Y366013D01*
X756955Y366179D01*
X758390Y365222D01*
X758557Y364390D01*
X769220Y357282D01*
X793309Y333192D01*
Y321107D01*
X793817Y320600D01*
G01X787137Y321120D02*
Y331131D01*
X765227Y353041D01*
X744112Y367117D01*
X722386Y371461D01*
Y371460D01*
X701514Y367286D01*
X680644Y363113D01*
X653736Y345241D01*
X637593Y334520D01*
X597939Y308183D01*
X595114Y304087D01*
X595113Y304086D01*
X592290Y299992D01*
X578849Y232810D01*
X588214Y185931D01*
X577016Y129933D01*
X568604Y117304D01*
X562953Y113534D01*
X549834D01*
X545056Y118312D01*
Y145881D01*
G02X547425Y148250I2369J0D01*
G01X548537D01*
G03X549015Y148448I0J676D01*
G03X549212Y148924I-477J476D01*
G01Y150394D01*
G01Y144882D02*
Y146135D01*
G03X548951Y146765I-891J0D01*
G03X548323Y147025I-628J-628D01*
G01X547425D01*
G03X546281Y145881I0J-1144D01*
G01Y118820D01*
X550342Y114759D01*
X562581D01*
X567720Y118187D01*
X575862Y130411D01*
X576200Y132103D01*
X575730Y132809D01*
X576068Y134500D01*
X576774Y134971D01*
X577112Y136662D01*
X576641Y137368D01*
X576980Y139060D01*
X577686Y139530D01*
X578024Y141222D01*
X577553Y141928D01*
X577891Y143619D01*
X578597Y144090D01*
X578936Y145782D01*
X578465Y146488D01*
X578803Y148179D01*
X579509Y148650D01*
X583317Y167692D01*
X582846Y168398D01*
X583184Y170090D01*
X583890Y170560D01*
X584229Y172252D01*
X583758Y172958D01*
X584096Y174649D01*
X584802Y175120D01*
X585140Y176812D01*
X584670Y177518D01*
X585008Y179209D01*
X585714Y179680D01*
X586052Y181371D01*
X585582Y182077D01*
X585920Y183769D01*
X586626Y184239D01*
X586964Y185931D01*
X577599Y232810D01*
X584367Y266642D01*
X591138Y300480D01*
X592692Y302735D01*
X594104Y304781D01*
X597064Y309074D01*
X636915Y335541D01*
X669203Y356985D01*
X680167Y364267D01*
X722386Y372711D01*
X726350Y371919D01*
X727056Y372389D01*
X728748Y372051D01*
X729218Y371345D01*
X730910Y371007D01*
X731616Y371477D01*
X733308Y371139D01*
X733778Y370433D01*
X735470Y370095D01*
X736176Y370565D01*
X737868Y370227D01*
X738338Y369521D01*
X740030Y369183D01*
X740736Y369653D01*
X742428Y369315D01*
X742898Y368609D01*
X744590Y368271D01*
X766008Y353994D01*
X788362Y331639D01*
Y321055D01*
X788817Y320600D01*
G01X778575Y300969D02*
Y302958D01*
X782116Y306499D01*
Y317901D01*
X781617Y318400D01*
G01X779800Y300969D02*
Y302450D01*
X783341Y305991D01*
Y317924D01*
X783817Y318400D01*
G01X774160Y302275D02*
Y310660D01*
X777116Y313616D01*
Y317901D01*
X776617Y318400D01*
G01X775385Y302275D02*
Y310152D01*
X778341Y313108D01*
Y317924D01*
X778817Y318400D01*
G01X766325Y306000D02*
Y308242D01*
X760110Y314457D01*
Y317908D01*
X759618Y318400D01*
G01X767550Y306000D02*
Y308750D01*
X761335Y314965D01*
Y317918D01*
X761817Y318400D01*
G01X763160Y301675D02*
Y304257D01*
X755191Y312226D01*
Y317826D01*
X754617Y318400D01*
G01X764385Y301675D02*
Y304765D01*
X756416Y312734D01*
Y317999D01*
X756817Y318400D01*
G01X755108Y306012D02*
X747118Y314002D01*
Y317899D01*
X746617Y318400D01*
G01X755975Y306879D02*
X748343Y314511D01*
Y317926D01*
X748817Y318400D01*
G01X753160Y298625D02*
Y303507D01*
X745747Y310920D01*
X744347D01*
X740509Y314758D01*
Y318008D01*
X740117Y318400D01*
G01X754385Y298625D02*
Y304015D01*
X746255Y312145D01*
X744855D01*
X741734Y315266D01*
Y317817D01*
X742317Y318400D01*
G01X791617D02*
X792116Y317901D01*
Y306716D01*
X787500Y302100D01*
G01X793817Y318400D02*
X793341Y317924D01*
Y306208D01*
X788367Y301234D01*
G01X785475Y304325D02*
X787116Y305966D01*
Y317901D01*
X786617Y318400D01*
G01X786341Y303458D02*
X788341Y305458D01*
Y317924D01*
X788817Y318400D01*
M02*
